FILE_TYPE = MACRO_DRAWING;
SET COLOR_WIRE YELLOW;
SET COLOR_PROP ORANGE;
SET COLOR_DOT WHITE;
SET COLOR_ARC YELLOW;
SET COLOR_BODY GREEN;
SET COLOR_NOTE PURPLE;
SET PROP_DISPLAY VALUE;
SET PAGE_NUMBER P15;
FORCEADD GND_SG..1
(-9050 7050);
FORCEPROP 3 LASTPIN (-9000 7100) SIG_NAME SG\g
J 0
(-8990 7110);
DISPLAY 0.659574 (-8990 7110);
PAINT MONO (-8990 7110);
DISPLAY INVISIBLE (-8990 7110);
FORCEPROP 1 LAST HDL_POWER SG
J 1
(-8995 6955);
DISPLAY 0.808511 (-8995 6955);
PAINT GREEN (-8995 6955);
FORCEPROP 2 LAST CDS_LIB cls
J 0
(-9050 7050);
DISPLAY INVISIBLE (-9050 7050);
FORCEPROP 1 LAST CDS_LMAN_SYM_OUTLINE 0,0,100,-50
J 0
(-9050 7050);
DISPLAY 0.468085 (-9050 7050);
PAINT GREEN (-9050 7050);
DISPLAY INVISIBLE (-9050 7050);
FORCEPROP 1 LAST BODY_TYPE PLUMBING
J 0
(-9035 7035);
DISPLAY 0.808511 (-9035 7035);
PAINT GREEN (-9035 7035);
DISPLAY INVISIBLE (-9035 7035);
FORCEPROP 1 LAST PATH I148
J 0
(-9015 7050);
DISPLAY 0.808511 (-9015 7050);
PAINT GREEN (-9015 7050);
DISPLAY INVISIBLE (-9015 7050);
FORCEADD CAPACITOR..2
(-9000 7400);
FORCEPROP 1 LAST $LOCATION C3
J 0
(-8900 7250);
DISPLAY 1.212766 (-8900 7250);
PAINT GREEN (-8900 7250);
FORCEPROP 0 LAST CDS_LOCATION C3
J 0
(-8950 7250);
DISPLAY 1.212766 (-8950 7250);
PAINT GREEN (-8950 7250);
DISPLAY INVISIBLE (-8950 7250);
FORCEPROP 0 LAST $SEC 1
J 0
(-8950 7550);
PAINT MONO (-8950 7550);
DISPLAY INVISIBLE (-8950 7550);
FORCEPROP 0 LAST CDS_SEC 1
J 0
(-8950 7550);
PAINT MONO (-8950 7550);
DISPLAY INVISIBLE (-8950 7550);
FORCEPROP 0 LASTPIN (-9000 7500) $PN 1
R 1
J 0
(-9010 7510);
DISPLAY 0.808511 (-9010 7510);
PAINT MONO (-9010 7510);
FORCEPROP 0 LASTPIN (-9000 7250) $PN 2
R 1
J 2
(-9010 7240);
DISPLAY 0.808511 (-9010 7240);
PAINT MONO (-9010 7240);
FORCEPROP 0 LAST VOLTAGE 25V
J 0
(-8900 7550);
DISPLAY 1.021277 (-8900 7550);
FORCEPROP 0 LAST PACKAGE 0402
J 0
(-8900 7450);
DISPLAY 1.021277 (-8900 7450);
FORCEPROP 1 LAST VALUE 0.1UF
J 0
(-8900 7350);
DISPLAY 1.212766 (-8900 7350);
PAINT GREEN (-8900 7350);
FORCEPROP 2 LAST CDS_LIB passive
J 0
(-9000 7400);
DISPLAY INVISIBLE (-9000 7400);
FORCEPROP 1 LAST CDS_LMAN_SYM_OUTLINE -50,0,50,-50
J 0
(-9000 7400);
DISPLAY 0.468085 (-9000 7400);
PAINT GREEN (-9000 7400);
DISPLAY INVISIBLE (-9000 7400);
FORCEPROP 1 LAST TOLERANCE 10%
J 0
(-9150 7500);
DISPLAY 1.212766 (-9150 7500);
PAINT GREEN (-9150 7500);
DISPLAY INVISIBLE (-9150 7500);
FORCEPROP 1 LAST CLS_PN G105-0B104-EK
J 0
(-9100 7450);
DISPLAY 1.212766 (-9100 7450);
PAINT GREEN (-9100 7450);
DISPLAY INVISIBLE (-9100 7450);
FORCEPROP 1 LAST PATH I156
J 0
(-9100 7450);
DISPLAY 1.212766 (-9100 7450);
PAINT GREEN (-9100 7450);
DISPLAY INVISIBLE (-9100 7450);
FORCEADD GND_SG..1
(-9000 8350);
FORCEPROP 3 LASTPIN (-8950 8400) SIG_NAME SG\g
J 0
(-8940 8410);
DISPLAY 0.659574 (-8940 8410);
PAINT MONO (-8940 8410);
DISPLAY INVISIBLE (-8940 8410);
FORCEPROP 1 LAST HDL_POWER SG
J 1
(-8945 8255);
DISPLAY 0.808511 (-8945 8255);
PAINT GREEN (-8945 8255);
FORCEPROP 1 LAST CDS_LMAN_SYM_OUTLINE 0,0,100,-50
J 0
(-9000 8350);
DISPLAY 0.468085 (-9000 8350);
PAINT GREEN (-9000 8350);
DISPLAY INVISIBLE (-9000 8350);
FORCEPROP 2 LAST CDS_LIB cls
J 0
(-9000 8350);
DISPLAY INVISIBLE (-9000 8350);
FORCEPROP 1 LAST BODY_TYPE PLUMBING
J 0
(-8985 8335);
DISPLAY 0.808511 (-8985 8335);
PAINT GREEN (-8985 8335);
DISPLAY INVISIBLE (-8985 8335);
FORCEPROP 1 LAST PATH I157
J 0
(-8965 8350);
DISPLAY 0.808511 (-8965 8350);
PAINT GREEN (-8965 8350);
DISPLAY INVISIBLE (-8965 8350);
FORCEADD GND_SG..1
(-11200 8400);
FORCEPROP 3 LASTPIN (-11150 8450) SIG_NAME SG\g
J 0
(-11140 8460);
DISPLAY 0.659574 (-11140 8460);
PAINT MONO (-11140 8460);
DISPLAY INVISIBLE (-11140 8460);
FORCEPROP 1 LAST HDL_POWER SG
J 1
(-11145 8305);
DISPLAY 0.808511 (-11145 8305);
PAINT GREEN (-11145 8305);
FORCEPROP 2 LAST CDS_LIB cls
J 0
(-11200 8400);
DISPLAY INVISIBLE (-11200 8400);
FORCEPROP 1 LAST CDS_LMAN_SYM_OUTLINE 0,0,100,-50
J 0
(-11200 8400);
DISPLAY 0.468085 (-11200 8400);
PAINT GREEN (-11200 8400);
DISPLAY INVISIBLE (-11200 8400);
FORCEPROP 1 LAST BODY_TYPE PLUMBING
J 0
(-11185 8385);
DISPLAY 0.808511 (-11185 8385);
PAINT GREEN (-11185 8385);
DISPLAY INVISIBLE (-11185 8385);
FORCEPROP 1 LAST PATH I158
J 0
(-11165 8400);
DISPLAY 0.808511 (-11165 8400);
PAINT GREEN (-11165 8400);
DISPLAY INVISIBLE (-11165 8400);
FORCEADD DIODE_2E..1
R 1
(-11150 8950);
PAINT WHITE (-11150 8950);
FORCEPROP 1 LAST $LOCATION CR10
R 1
J 2
(-11250 8850);
DISPLAY 1.212766 (-11250 8850);
PAINT GREEN (-11250 8850);
FORCEPROP 0 LAST CDS_LOCATION CR10
R 1
J 0
(-11050 9250);
DISPLAY 1.021277 (-11050 9250);
DISPLAY INVISIBLE (-11050 9250);
FORCEPROP 0 LAST $SEC 1
R 1
J 0
(-11050 9250);
DISPLAY 0.680851 (-11050 9250);
PAINT MONO (-11050 9250);
DISPLAY INVISIBLE (-11050 9250);
FORCEPROP 0 LAST CDS_SEC 1
R 1
J 0
(-11050 9250);
DISPLAY 1.021277 (-11050 9250);
DISPLAY INVISIBLE (-11050 9250);
FORCEPROP 0 LASTPIN (-11150 8700) $PN A
R 1
J 2
(-11160 8690);
DISPLAY 0.680851 (-11160 8690);
PAINT MONO (-11160 8690);
FORCEPROP 0 LASTPIN (-11150 9200) $PN C
R 1
J 0
(-11160 9210);
DISPLAY 0.680851 (-11160 9210);
PAINT MONO (-11160 9210);
FORCEPROP 1 LAST CLS_PN G122-10190-01
R 1
J 0
(-11000 8600);
DISPLAY 1.212766 (-11000 8600);
PAINT GREEN (-11000 8600);
FORCEPROP 0 LAST PART_NUMBER SMDJ12A
R 1
J 0
(-10900 8600);
DISPLAY 1.021277 (-10900 8600);
FORCEPROP 2 LAST CDS_LIB discrete
J 0
(-11150 8950);
DISPLAY INVISIBLE (-11150 8950);
FORCEPROP 1 LAST CDS_LMAN_SYM_OUTLINE -50,100,50,-100
R 1
J 0
(-11150 8950);
DISPLAY 0.468085 (-11150 8950);
PAINT GREEN (-11150 8950);
DISPLAY INVISIBLE (-11150 8950);
FORCEPROP 1 LAST PATH I159
R 1
J 0
(-11350 9050);
DISPLAY 1.212766 (-11350 9050);
PAINT GREEN (-11350 9050);
DISPLAY INVISIBLE (-11350 9050);
FORCEADD CAPACITOR..2
(-8950 9000);
FORCEPROP 1 LAST $LOCATION C2
J 0
(-8850 8950);
DISPLAY 1.212766 (-8850 8950);
PAINT GREEN (-8850 8950);
FORCEPROP 0 LAST CDS_LOCATION C2
J 0
(-8900 9150);
DISPLAY 1.021277 (-8900 9150);
DISPLAY INVISIBLE (-8900 9150);
FORCEPROP 0 LAST $SEC 1
J 0
(-8900 9150);
DISPLAY 0.680851 (-8900 9150);
PAINT MONO (-8900 9150);
DISPLAY INVISIBLE (-8900 9150);
FORCEPROP 0 LAST CDS_SEC 1
J 0
(-8900 9150);
DISPLAY 1.021277 (-8900 9150);
DISPLAY INVISIBLE (-8900 9150);
FORCEPROP 0 LASTPIN (-8950 9100) $PN 1
R 1
J 0
(-8960 9110);
DISPLAY 0.680851 (-8960 9110);
PAINT MONO (-8960 9110);
FORCEPROP 0 LASTPIN (-8950 8850) $PN 2
R 1
J 2
(-8960 8840);
DISPLAY 0.680851 (-8960 8840);
PAINT MONO (-8960 8840);
FORCEPROP 0 LAST PACKAGE 0402
J 0
(-8900 9200);
DISPLAY 1.021277 (-8900 9200);
FORCEPROP 0 LAST VOLTAGE 25V
J 0
(-8900 9300);
DISPLAY 1.021277 (-8900 9300);
FORCEPROP 1 LAST VALUE 0.1UF
J 0
(-8900 9050);
DISPLAY 1.212766 (-8900 9050);
PAINT GREEN (-8900 9050);
FORCEPROP 1 LAST TOLERANCE 10%
J 0
(-9100 9100);
DISPLAY 1.212766 (-9100 9100);
PAINT GREEN (-9100 9100);
DISPLAY INVISIBLE (-9100 9100);
FORCEPROP 2 LAST CDS_LIB passive
J 0
(-8950 9000);
DISPLAY INVISIBLE (-8950 9000);
FORCEPROP 1 LAST CDS_LMAN_SYM_OUTLINE -50,0,50,-50
J 0
(-8950 9000);
DISPLAY 0.468085 (-8950 9000);
PAINT GREEN (-8950 9000);
DISPLAY INVISIBLE (-8950 9000);
FORCEPROP 1 LAST CLS_PN G105-0B104-EK
J 0
(-9050 9050);
DISPLAY 1.212766 (-9050 9050);
PAINT GREEN (-9050 9050);
DISPLAY INVISIBLE (-9050 9050);
FORCEPROP 1 LAST PATH I160
J 0
(-9050 9050);
DISPLAY 1.212766 (-9050 9050);
PAINT GREEN (-9050 9050);
DISPLAY INVISIBLE (-9050 9050);
FORCEADD GND_SG..1
(-8500 7050);
FORCEPROP 3 LASTPIN (-8450 7100) SIG_NAME SG\g
J 0
(-8440 7110);
DISPLAY 0.659574 (-8440 7110);
PAINT MONO (-8440 7110);
DISPLAY INVISIBLE (-8440 7110);
FORCEPROP 1 LAST HDL_POWER SG
J 1
(-8445 6955);
DISPLAY 0.808511 (-8445 6955);
PAINT GREEN (-8445 6955);
FORCEPROP 2 LAST CDS_LIB cls
J 0
(-8500 7050);
DISPLAY INVISIBLE (-8500 7050);
FORCEPROP 1 LAST CDS_LMAN_SYM_OUTLINE 0,0,100,-50
J 0
(-8500 7050);
DISPLAY 0.468085 (-8500 7050);
PAINT GREEN (-8500 7050);
DISPLAY INVISIBLE (-8500 7050);
FORCEPROP 1 LAST BODY_TYPE PLUMBING
J 0
(-8485 7035);
DISPLAY 0.808511 (-8485 7035);
PAINT GREEN (-8485 7035);
DISPLAY INVISIBLE (-8485 7035);
FORCEPROP 1 LAST PATH I166
J 0
(-8465 7050);
DISPLAY 0.808511 (-8465 7050);
PAINT GREEN (-8465 7050);
DISPLAY INVISIBLE (-8465 7050);
FORCEADD GND_SG..1
(-7900 7050);
FORCEPROP 3 LASTPIN (-7850 7100) SIG_NAME SG\g
J 0
(-7840 7110);
DISPLAY 0.659574 (-7840 7110);
PAINT MONO (-7840 7110);
DISPLAY INVISIBLE (-7840 7110);
FORCEPROP 1 LAST HDL_POWER SG
J 1
(-7845 6955);
DISPLAY 0.808511 (-7845 6955);
PAINT GREEN (-7845 6955);
FORCEPROP 1 LAST CDS_LMAN_SYM_OUTLINE 0,0,100,-50
J 0
(-7900 7050);
DISPLAY 0.468085 (-7900 7050);
PAINT GREEN (-7900 7050);
DISPLAY INVISIBLE (-7900 7050);
FORCEPROP 2 LAST CDS_LIB cls
J 0
(-7900 7050);
DISPLAY INVISIBLE (-7900 7050);
FORCEPROP 1 LAST BODY_TYPE PLUMBING
J 0
(-7885 7035);
DISPLAY 0.808511 (-7885 7035);
PAINT GREEN (-7885 7035);
DISPLAY INVISIBLE (-7885 7035);
FORCEPROP 1 LAST PATH I167
J 0
(-7865 7050);
DISPLAY 0.808511 (-7865 7050);
PAINT GREEN (-7865 7050);
DISPLAY INVISIBLE (-7865 7050);
FORCEADD GND_SG..1
(-5250 6500);
FORCEPROP 3 LASTPIN (-5200 6550) SIG_NAME SG\g
J 0
(-5190 6560);
DISPLAY 0.659574 (-5190 6560);
PAINT MONO (-5190 6560);
DISPLAY INVISIBLE (-5190 6560);
FORCEPROP 1 LAST HDL_POWER SG
J 1
(-5195 6405);
DISPLAY 0.808511 (-5195 6405);
PAINT GREEN (-5195 6405);
FORCEPROP 2 LAST CDS_LIB cls
J 0
(-5250 6500);
DISPLAY INVISIBLE (-5250 6500);
FORCEPROP 1 LAST CDS_LMAN_SYM_OUTLINE 0,0,100,-50
J 0
(-5250 6500);
DISPLAY 0.468085 (-5250 6500);
PAINT GREEN (-5250 6500);
DISPLAY INVISIBLE (-5250 6500);
FORCEPROP 1 LAST BODY_TYPE PLUMBING
J 0
(-5235 6485);
DISPLAY 0.808511 (-5235 6485);
PAINT GREEN (-5235 6485);
DISPLAY INVISIBLE (-5235 6485);
FORCEPROP 1 LAST PATH I168
J 0
(-5215 6500);
DISPLAY 0.808511 (-5215 6500);
PAINT GREEN (-5215 6500);
DISPLAY INVISIBLE (-5215 6500);
FORCEADD RESISTOR..2
(-8450 7400);
FORCEPROP 1 LAST $LOCATION R5
J 0
(-8400 7250);
DISPLAY 1.212766 (-8400 7250);
PAINT GREEN (-8400 7250);
FORCEPROP 0 LAST CDS_LOCATION R5
J 0
(-8400 7550);
DISPLAY 1.021277 (-8400 7550);
DISPLAY INVISIBLE (-8400 7550);
FORCEPROP 0 LAST $SEC 1
J 0
(-8400 7550);
PAINT MONO (-8400 7550);
DISPLAY INVISIBLE (-8400 7550);
FORCEPROP 0 LAST CDS_SEC 1
J 0
(-8400 7550);
PAINT MONO (-8400 7550);
DISPLAY INVISIBLE (-8400 7550);
FORCEPROP 0 LASTPIN (-8450 7500) $PN 1
R 1
J 0
(-8460 7510);
DISPLAY 0.808511 (-8460 7510);
PAINT MONO (-8460 7510);
FORCEPROP 0 LASTPIN (-8450 7250) $PN 2
R 1
J 2
(-8460 7240);
DISPLAY 0.808511 (-8460 7240);
PAINT MONO (-8460 7240);
FORCEPROP 0 LAST NO_ASSY TRUE
J 0
(-8400 7350);
DISPLAY 0.808511 (-8400 7350);
DISPLAY BOTH (-8400 7350);
FORCEPROP 1 LAST VALUE 10KOHM
J 0
(-8400 7450);
DISPLAY 1.212766 (-8400 7450);
PAINT GREEN (-8400 7450);
FORCEPROP 0 LAST PACKAGE 0402
J 0
(-8400 7600);
DISPLAY 1.021277 (-8400 7600);
FORCEPROP 1 LAST CDS_LMAN_SYM_OUTLINE -50,50,50,-100
J 0
(-8450 7400);
DISPLAY 0.468085 (-8450 7400);
PAINT GREEN (-8450 7400);
DISPLAY INVISIBLE (-8450 7400);
FORCEPROP 2 LAST CDS_LIB passive
J 0
(-8450 7400);
DISPLAY INVISIBLE (-8450 7400);
FORCEPROP 1 LAST CLS_PN G155-11002-01
J 0
(-8586 7600);
DISPLAY 1.212766 (-8586 7600);
PAINT GREEN (-8586 7600);
DISPLAY INVISIBLE (-8586 7600);
FORCEPROP 1 LAST TOLERANCE 1%
J 0
(-8647 7655);
DISPLAY 1.212766 (-8647 7655);
PAINT GREEN (-8647 7655);
DISPLAY INVISIBLE (-8647 7655);
FORCEPROP 1 LAST PATH I169
J 0
(-8647 7505);
DISPLAY 1.212766 (-8647 7505);
PAINT GREEN (-8647 7505);
DISPLAY INVISIBLE (-8647 7505);
FORCEADD RESISTOR..2
(-8450 8850);
FORCEPROP 1 LAST $LOCATION R4
J 0
(-8400 8700);
DISPLAY 1.212766 (-8400 8700);
PAINT GREEN (-8400 8700);
FORCEPROP 2 LAST CDS_LOCATION R4
J 0
(-8600 9050);
DISPLAY 1.021277 (-8600 9050);
DISPLAY INVISIBLE (-8600 9050);
FORCEPROP 2 LAST $SEC 1
J 0
(-8600 9050);
DISPLAY 0.680851 (-8600 9050);
PAINT MONO (-8600 9050);
DISPLAY INVISIBLE (-8600 9050);
FORCEPROP 2 LAST CDS_SEC 1
J 0
(-8600 9050);
DISPLAY 1.021277 (-8600 9050);
DISPLAY INVISIBLE (-8600 9050);
FORCEPROP 2 LASTPIN (-8450 8950) $PN 1
R 1
J 0
(-8460 8960);
DISPLAY 0.680851 (-8460 8960);
PAINT MONO (-8460 8960);
FORCEPROP 2 LASTPIN (-8450 8700) $PN 2
R 1
J 2
(-8460 8690);
DISPLAY 0.680851 (-8460 8690);
PAINT MONO (-8460 8690);
FORCEPROP 0 LAST PACKAGE 0402
J 0
(-8400 9050);
DISPLAY 1.021277 (-8400 9050);
FORCEPROP 1 LAST VALUE 10KOHM
J 0
(-8400 8900);
DISPLAY 1.212766 (-8400 8900);
PAINT GREEN (-8400 8900);
FORCEPROP 0 LAST NO_ASSY TRUE
J 0
(-8350 8800);
DISPLAY 1.021277 (-8350 8800);
DISPLAY BOTH (-8350 8800);
FORCEPROP 2 LAST CDS_LIB passive
J 0
(-8450 8850);
DISPLAY INVISIBLE (-8450 8850);
FORCEPROP 1 LAST CDS_LMAN_SYM_OUTLINE -50,50,50,-100
J 0
(-8450 8850);
DISPLAY 0.468085 (-8450 8850);
PAINT GREEN (-8450 8850);
DISPLAY INVISIBLE (-8450 8850);
FORCEPROP 1 LAST CLS_PN G155-11002-01
J 0
(-8586 9050);
DISPLAY 1.212766 (-8586 9050);
PAINT GREEN (-8586 9050);
DISPLAY INVISIBLE (-8586 9050);
FORCEPROP 1 LAST TOLERANCE 1%
J 0
(-8647 9105);
DISPLAY 1.212766 (-8647 9105);
PAINT GREEN (-8647 9105);
DISPLAY INVISIBLE (-8647 9105);
FORCEPROP 1 LAST PATH I170
J 0
(-8647 8955);
DISPLAY 1.212766 (-8647 8955);
PAINT GREEN (-8647 8955);
DISPLAY INVISIBLE (-8647 8955);
FORCEADD RESISTOR..1
(-7550 7500);
FORCEPROP 1 LAST $LOCATION R46
J 2
(-7651 7505);
DISPLAY 1.212766 (-7651 7505);
PAINT GREEN (-7651 7505);
FORCEPROP 0 LAST CDS_LOCATION R46
J 0
(-7650 7600);
DISPLAY 1.021277 (-7650 7600);
DISPLAY INVISIBLE (-7650 7600);
FORCEPROP 0 LAST $SEC 1
J 0
(-7400 7600);
DISPLAY 0.680851 (-7400 7600);
PAINT MONO (-7400 7600);
DISPLAY INVISIBLE (-7400 7600);
FORCEPROP 0 LAST CDS_SEC 1
J 0
(-7650 7600);
DISPLAY 1.021277 (-7650 7600);
DISPLAY INVISIBLE (-7650 7600);
FORCEPROP 0 LASTPIN (-7650 7500) $PN 1
J 2
(-7660 7510);
DISPLAY 0.680851 (-7660 7510);
PAINT MONO (-7660 7510);
FORCEPROP 0 LASTPIN (-7400 7500) $PN 2
J 0
(-7390 7510);
DISPLAY 0.680851 (-7390 7510);
PAINT MONO (-7390 7510);
FORCEPROP 1 LAST VALUE 26.7K
J 0
(-7350 7500);
DISPLAY 1.212766 (-7350 7500);
PAINT GREEN (-7350 7500);
FORCEPROP 0 LAST PACKAGE 0402
J 0
(-7600 7400);
DISPLAY 1.021277 (-7600 7400);
FORCEPROP 1 LAST CLS_PN G155-02672-01
J 0
(-7686 7700);
DISPLAY 1.212766 (-7686 7700);
PAINT GREEN (-7686 7700);
DISPLAY INVISIBLE (-7686 7700);
FORCEPROP 1 LAST PATH I171
J 0
(-7747 7605);
DISPLAY 1.212766 (-7747 7605);
PAINT GREEN (-7747 7605);
DISPLAY INVISIBLE (-7747 7605);
FORCEPROP 1 LAST TOLERANCE 1%
J 0
(-7747 7755);
DISPLAY 1.212766 (-7747 7755);
PAINT GREEN (-7747 7755);
DISPLAY INVISIBLE (-7747 7755);
FORCEPROP 2 LAST CDS_LIB passive
J 0
(-7550 7500);
DISPLAY INVISIBLE (-7550 7500);
FORCEPROP 1 LAST CDS_LMAN_SYM_OUTLINE -50,50,100,-50
J 0
(-7550 7500);
DISPLAY 0.468085 (-7550 7500);
PAINT GREEN (-7550 7500);
DISPLAY INVISIBLE (-7550 7500);
FORCEADD CAPACITOR..1
(-7550 7700);
FORCEPROP 1 LAST $LOCATION C4
J 2
(-7700 7700);
DISPLAY 1.212766 (-7700 7700);
PAINT GREEN (-7700 7700);
FORCEPROP 0 LAST CDS_LOCATION C4
J 0
(-7400 8000);
DISPLAY 1.021277 (-7400 8000);
DISPLAY INVISIBLE (-7400 8000);
FORCEPROP 0 LAST $SEC 1
J 0
(-7650 7850);
PAINT MONO (-7650 7850);
DISPLAY INVISIBLE (-7650 7850);
FORCEPROP 0 LAST CDS_SEC 1
J 0
(-7650 7850);
PAINT MONO (-7650 7850);
DISPLAY INVISIBLE (-7650 7850);
FORCEPROP 0 LASTPIN (-7650 7700) $PN 1
J 2
(-7660 7710);
DISPLAY 0.808511 (-7660 7710);
PAINT MONO (-7660 7710);
FORCEPROP 0 LASTPIN (-7400 7700) $PN 2
J 0
(-7390 7710);
DISPLAY 0.808511 (-7390 7710);
PAINT MONO (-7390 7710);
FORCEPROP 0 LAST PACKAGE 0201
J 0
(-7600 7800);
DISPLAY 1.021277 (-7600 7800);
FORCEPROP 1 LAST VALUE 0.22UF
J 0
(-7700 7600);
DISPLAY 1.212766 (-7700 7600);
PAINT GREEN (-7700 7600);
FORCEPROP 0 LAST VOLTAGE 6.3V
J 0
(-7300 7750);
DISPLAY 1.021277 (-7300 7750);
FORCEPROP 1 LAST TOLERANCE 10%
J 2
(-7650 7800);
DISPLAY 1.212766 (-7650 7800);
PAINT GREEN (-7650 7800);
DISPLAY INVISIBLE (-7650 7800);
FORCEPROP 1 LAST CDS_LMAN_SYM_OUTLINE 0,50,50,-50
J 0
(-7550 7700);
DISPLAY 0.468085 (-7550 7700);
PAINT GREEN (-7550 7700);
DISPLAY INVISIBLE (-7550 7700);
FORCEPROP 2 LAST CDS_LIB passive
J 0
(-7550 7700);
DISPLAY INVISIBLE (-7550 7700);
FORCEPROP 1 LAST CLS_PN G104-0F224-BK
J 2
(-7600 7800);
DISPLAY 1.212766 (-7600 7800);
PAINT GREEN (-7600 7800);
DISPLAY INVISIBLE (-7600 7800);
FORCEPROP 1 LAST PATH I172
J 2
(-7600 7800);
DISPLAY 1.212766 (-7600 7800);
PAINT GREEN (-7600 7800);
DISPLAY INVISIBLE (-7600 7800);
FORCEADD RESISTOR..1
(-7500 7900);
FORCEPROP 1 LAST $LOCATION R8
J 2
(-7601 7955);
DISPLAY 1.212766 (-7601 7955);
PAINT GREEN (-7601 7955);
FORCEPROP 0 LAST CDS_LOCATION R8
J 0
(-7600 8050);
DISPLAY 1.021277 (-7600 8050);
DISPLAY INVISIBLE (-7600 8050);
FORCEPROP 0 LAST $SEC 1
J 0
(-7600 8050);
DISPLAY 0.680851 (-7600 8050);
PAINT MONO (-7600 8050);
DISPLAY INVISIBLE (-7600 8050);
FORCEPROP 0 LAST CDS_SEC 1
J 0
(-7600 8050);
DISPLAY 1.021277 (-7600 8050);
DISPLAY INVISIBLE (-7600 8050);
FORCEPROP 0 LASTPIN (-7600 7900) $PN 1
J 2
(-7610 7910);
DISPLAY 0.680851 (-7610 7910);
PAINT MONO (-7610 7910);
FORCEPROP 0 LASTPIN (-7350 7900) $PN 2
J 0
(-7340 7910);
DISPLAY 0.680851 (-7340 7910);
PAINT MONO (-7340 7910);
FORCEPROP 1 LAST VALUE 0OHM
J 0
(-7300 7950);
DISPLAY 0.978723 (-7300 7950);
PAINT GREEN (-7300 7950);
FORCEPROP 0 LAST PACKAGE 0402
J 0
(-7600 7950);
DISPLAY 1.021277 (-7600 7950);
FORCEPROP 2 LAST CDS_LIB passive
J 0
(-7500 7900);
DISPLAY INVISIBLE (-7500 7900);
FORCEPROP 1 LAST CDS_LMAN_SYM_OUTLINE -50,50,100,-50
J 0
(-7500 7900);
DISPLAY 0.468085 (-7500 7900);
PAINT GREEN (-7500 7900);
DISPLAY INVISIBLE (-7500 7900);
FORCEPROP 1 LAST CLS_PN G155-100R0-J0
J 0
(-7636 8100);
DISPLAY 1.212766 (-7636 8100);
PAINT GREEN (-7636 8100);
DISPLAY INVISIBLE (-7636 8100);
FORCEPROP 1 LAST TOLERANCE -
J 0
(-7697 8155);
DISPLAY 1.212766 (-7697 8155);
PAINT GREEN (-7697 8155);
DISPLAY INVISIBLE (-7697 8155);
FORCEPROP 1 LAST PATH I173
J 0
(-7697 8005);
DISPLAY 1.212766 (-7697 8005);
PAINT GREEN (-7697 8005);
DISPLAY INVISIBLE (-7697 8005);
FORCEADD RESISTOR..1
(-7500 8100);
FORCEPROP 1 LAST $LOCATION R7
J 2
(-7601 8155);
DISPLAY 1.212766 (-7601 8155);
PAINT GREEN (-7601 8155);
FORCEPROP 2 LAST CDS_LOCATION R7
J 0
(-7650 8300);
DISPLAY 1.021277 (-7650 8300);
DISPLAY INVISIBLE (-7650 8300);
FORCEPROP 2 LAST $SEC 1
J 0
(-7650 8300);
DISPLAY 0.680851 (-7650 8300);
PAINT MONO (-7650 8300);
DISPLAY INVISIBLE (-7650 8300);
FORCEPROP 2 LAST CDS_SEC 1
J 0
(-7650 8300);
DISPLAY 1.021277 (-7650 8300);
DISPLAY INVISIBLE (-7650 8300);
FORCEPROP 2 LASTPIN (-7600 8100) $PN 1
J 2
(-7610 8110);
DISPLAY 0.680851 (-7610 8110);
PAINT MONO (-7610 8110);
FORCEPROP 2 LASTPIN (-7350 8100) $PN 2
J 0
(-7340 8110);
DISPLAY 0.680851 (-7340 8110);
PAINT MONO (-7340 8110);
FORCEPROP 0 LAST PACKAGE 0402
J 0
(-7550 8150);
DISPLAY 1.021277 (-7550 8150);
FORCEPROP 1 LAST VALUE 0OHM
J 0
(-7300 8150);
DISPLAY 0.978723 (-7300 8150);
PAINT GREEN (-7300 8150);
FORCEPROP 1 LAST CDS_LMAN_SYM_OUTLINE -50,50,100,-50
J 0
(-7500 8100);
DISPLAY 0.468085 (-7500 8100);
PAINT GREEN (-7500 8100);
DISPLAY INVISIBLE (-7500 8100);
FORCEPROP 2 LAST CDS_LIB passive
J 0
(-7500 8100);
DISPLAY INVISIBLE (-7500 8100);
FORCEPROP 1 LAST CLS_PN G155-100R0-J0
J 0
(-7636 8300);
DISPLAY 1.212766 (-7636 8300);
PAINT GREEN (-7636 8300);
DISPLAY INVISIBLE (-7636 8300);
FORCEPROP 1 LAST TOLERANCE -
J 0
(-7697 8355);
DISPLAY 1.212766 (-7697 8355);
PAINT GREEN (-7697 8355);
DISPLAY INVISIBLE (-7697 8355);
FORCEPROP 1 LAST PATH I174
J 0
(-7697 8205);
DISPLAY 1.212766 (-7697 8205);
PAINT GREEN (-7697 8205);
DISPLAY INVISIBLE (-7697 8205);
FORCEADD RESISTOR..2
(-4650 6950);
FORCEPROP 1 LAST $LOCATION R10
J 0
(-4600 6800);
DISPLAY 1.212766 (-4600 6800);
PAINT GREEN (-4600 6800);
FORCEPROP 0 LAST CDS_LOCATION R10
J 0
(-4650 7150);
DISPLAY 1.021277 (-4650 7150);
DISPLAY INVISIBLE (-4650 7150);
FORCEPROP 0 LAST $SEC 1
J 0
(-4650 7150);
PAINT MONO (-4650 7150);
DISPLAY INVISIBLE (-4650 7150);
FORCEPROP 0 LAST CDS_SEC 1
J 0
(-4650 7150);
PAINT MONO (-4650 7150);
DISPLAY INVISIBLE (-4650 7150);
FORCEPROP 0 LASTPIN (-4650 7050) $PN 1
R 1
J 0
(-4660 7060);
DISPLAY 0.808511 (-4660 7060);
PAINT MONO (-4660 7060);
FORCEPROP 0 LASTPIN (-4650 6800) $PN 2
R 1
J 2
(-4660 6790);
DISPLAY 0.808511 (-4660 6790);
PAINT MONO (-4660 6790);
FORCEPROP 0 LAST PACKAGE 0402
J 0
(-4600 7150);
DISPLAY 1.021277 (-4600 7150);
FORCEPROP 1 LAST VALUE 10KOHM
J 0
(-4650 7050);
DISPLAY 1.212766 (-4650 7050);
PAINT GREEN (-4650 7050);
FORCEPROP 1 LAST PATH I183
J 0
(-4847 7055);
DISPLAY 1.212766 (-4847 7055);
PAINT GREEN (-4847 7055);
DISPLAY INVISIBLE (-4847 7055);
FORCEPROP 1 LAST TOLERANCE 1%
J 0
(-4847 7205);
DISPLAY 1.212766 (-4847 7205);
PAINT GREEN (-4847 7205);
DISPLAY INVISIBLE (-4847 7205);
FORCEPROP 1 LAST CLS_PN G155-11002-01
J 0
(-4786 7150);
DISPLAY 1.212766 (-4786 7150);
PAINT GREEN (-4786 7150);
DISPLAY INVISIBLE (-4786 7150);
FORCEPROP 2 LAST CDS_LIB passive
J 0
(-4650 6950);
DISPLAY INVISIBLE (-4650 6950);
FORCEPROP 1 LAST CDS_LMAN_SYM_OUTLINE -50,50,50,-100
J 0
(-4650 6950);
DISPLAY 0.468085 (-4650 6950);
PAINT GREEN (-4650 6950);
DISPLAY INVISIBLE (-4650 6950);
FORCEADD GND_SG..1
(-4300 6500);
FORCEPROP 3 LASTPIN (-4250 6550) SIG_NAME SG\g
J 0
(-4240 6560);
DISPLAY 0.659574 (-4240 6560);
PAINT MONO (-4240 6560);
DISPLAY INVISIBLE (-4240 6560);
FORCEPROP 1 LAST HDL_POWER SG
J 1
(-4245 6405);
DISPLAY 0.808511 (-4245 6405);
PAINT GREEN (-4245 6405);
FORCEPROP 1 LAST PATH I184
J 0
(-4265 6500);
DISPLAY 0.808511 (-4265 6500);
PAINT GREEN (-4265 6500);
DISPLAY INVISIBLE (-4265 6500);
FORCEPROP 1 LAST BODY_TYPE PLUMBING
J 0
(-4285 6485);
DISPLAY 0.808511 (-4285 6485);
PAINT GREEN (-4285 6485);
DISPLAY INVISIBLE (-4285 6485);
FORCEPROP 2 LAST CDS_LIB cls
J 0
(-4300 6500);
DISPLAY INVISIBLE (-4300 6500);
FORCEPROP 1 LAST CDS_LMAN_SYM_OUTLINE 0,0,100,-50
J 0
(-4300 6500);
DISPLAY 0.468085 (-4300 6500);
PAINT GREEN (-4300 6500);
DISPLAY INVISIBLE (-4300 6500);
FORCEADD CAPACITOR..2
(-4250 6950);
FORCEPROP 1 LAST $LOCATION C7
J 0
(-4150 6750);
DISPLAY 1.212766 (-4150 6750);
PAINT GREEN (-4150 6750);
FORCEPROP 0 LAST CDS_LOCATION C7
J 0
(-4200 7100);
DISPLAY 1.021277 (-4200 7100);
DISPLAY INVISIBLE (-4200 7100);
FORCEPROP 0 LAST $SEC 1
J 0
(-4200 7100);
PAINT MONO (-4200 7100);
DISPLAY INVISIBLE (-4200 7100);
FORCEPROP 0 LAST CDS_SEC 1
J 0
(-4200 7100);
PAINT MONO (-4200 7100);
DISPLAY INVISIBLE (-4200 7100);
FORCEPROP 0 LASTPIN (-4250 7050) $PN 1
R 1
J 0
(-4260 7060);
DISPLAY 0.808511 (-4260 7060);
PAINT MONO (-4260 7060);
FORCEPROP 0 LASTPIN (-4250 6800) $PN 2
R 1
J 2
(-4260 6790);
DISPLAY 0.808511 (-4260 6790);
PAINT MONO (-4260 6790);
FORCEPROP 1 LAST VALUE 0.1UF
J 0
(-4150 6950);
DISPLAY 1.212766 (-4150 6950);
PAINT GREEN (-4150 6950);
FORCEPROP 0 LAST VOLTAGE 25V
J 0
(-4150 7050);
DISPLAY 1.021277 (-4150 7050);
FORCEPROP 0 LAST PACKAGE 0402
J 0
(-4050 6850);
DISPLAY 1.021277 (-4050 6850);
FORCEPROP 1 LAST PATH I185
J 0
(-4350 7000);
DISPLAY 1.212766 (-4350 7000);
PAINT GREEN (-4350 7000);
DISPLAY INVISIBLE (-4350 7000);
FORCEPROP 1 LAST CDS_LMAN_SYM_OUTLINE -50,0,50,-50
J 0
(-4250 6950);
DISPLAY 0.468085 (-4250 6950);
PAINT GREEN (-4250 6950);
DISPLAY INVISIBLE (-4250 6950);
FORCEPROP 2 LAST CDS_LIB passive
J 0
(-4250 6950);
DISPLAY INVISIBLE (-4250 6950);
FORCEPROP 1 LAST TOLERANCE 10%
J 0
(-4400 7050);
DISPLAY 1.212766 (-4400 7050);
PAINT GREEN (-4400 7050);
DISPLAY INVISIBLE (-4400 7050);
FORCEPROP 1 LAST CLS_PN G105-0B104-EK
J 0
(-4350 7000);
DISPLAY 1.212766 (-4350 7000);
PAINT GREEN (-4350 7000);
DISPLAY INVISIBLE (-4350 7000);
FORCEADD RESISTOR..2
(-3600 7250);
FORCEPROP 1 LAST $LOCATION R14
J 0
(-3550 7100);
DISPLAY 1.212766 (-3550 7100);
PAINT GREEN (-3550 7100);
FORCEPROP 0 LAST CDS_LOCATION R14
J 0
(-3550 7400);
DISPLAY 1.021277 (-3550 7400);
DISPLAY INVISIBLE (-3550 7400);
FORCEPROP 0 LAST $SEC 1
J 0
(-3550 7400);
PAINT MONO (-3550 7400);
DISPLAY INVISIBLE (-3550 7400);
FORCEPROP 0 LAST CDS_SEC 1
J 0
(-3550 7400);
PAINT MONO (-3550 7400);
DISPLAY INVISIBLE (-3550 7400);
FORCEPROP 0 LASTPIN (-3600 7350) $PN 1
R 1
J 0
(-3610 7360);
DISPLAY 0.808511 (-3610 7360);
PAINT MONO (-3610 7360);
FORCEPROP 0 LASTPIN (-3600 7100) $PN 2
R 1
J 2
(-3610 7090);
DISPLAY 0.808511 (-3610 7090);
PAINT MONO (-3610 7090);
FORCEPROP 1 LAST VALUE 3.92KOHM
J 0
(-3550 7300);
DISPLAY 1.212766 (-3550 7300);
PAINT GREEN (-3550 7300);
FORCEPROP 0 LAST PACKAGE 0402
J 0
(-3550 7450);
DISPLAY 1.021277 (-3550 7450);
FORCEPROP 1 LAST CLS_PN G155-03921-01
J 0
(-3736 7450);
DISPLAY 1.212766 (-3736 7450);
PAINT GREEN (-3736 7450);
DISPLAY INVISIBLE (-3736 7450);
FORCEPROP 2 LAST CDS_LIB passive
J 0
(-3600 7250);
DISPLAY INVISIBLE (-3600 7250);
FORCEPROP 1 LAST CDS_LMAN_SYM_OUTLINE -50,50,50,-100
J 0
(-3600 7250);
DISPLAY 0.468085 (-3600 7250);
PAINT GREEN (-3600 7250);
DISPLAY INVISIBLE (-3600 7250);
FORCEPROP 1 LAST TOLERANCE 1%
J 0
(-3797 7505);
DISPLAY 1.212766 (-3797 7505);
PAINT GREEN (-3797 7505);
DISPLAY INVISIBLE (-3797 7505);
FORCEPROP 1 LAST PATH I186
J 0
(-3797 7355);
DISPLAY 1.212766 (-3797 7355);
PAINT GREEN (-3797 7355);
DISPLAY INVISIBLE (-3797 7355);
FORCEADD GND_SG..1
(-3100 6750);
FORCEPROP 3 LASTPIN (-3050 6800) SIG_NAME SG\g
J 0
(-3040 6810);
DISPLAY 0.659574 (-3040 6810);
PAINT MONO (-3040 6810);
DISPLAY INVISIBLE (-3040 6810);
FORCEPROP 1 LAST HDL_POWER SG
J 1
(-3045 6655);
DISPLAY 0.808511 (-3045 6655);
PAINT GREEN (-3045 6655);
FORCEPROP 1 LAST CDS_LMAN_SYM_OUTLINE 0,0,100,-50
J 0
(-3100 6750);
DISPLAY 0.468085 (-3100 6750);
PAINT GREEN (-3100 6750);
DISPLAY INVISIBLE (-3100 6750);
FORCEPROP 2 LAST CDS_LIB cls
J 0
(-3100 6750);
DISPLAY INVISIBLE (-3100 6750);
FORCEPROP 1 LAST BODY_TYPE PLUMBING
J 0
(-3085 6735);
DISPLAY 0.808511 (-3085 6735);
PAINT GREEN (-3085 6735);
DISPLAY INVISIBLE (-3085 6735);
FORCEPROP 1 LAST PATH I187
J 0
(-3065 6750);
DISPLAY 0.808511 (-3065 6750);
PAINT GREEN (-3065 6750);
DISPLAY INVISIBLE (-3065 6750);
FORCEADD RESISTOR..2
(-3050 7250);
FORCEPROP 1 LAST $LOCATION R16
J 0
(-3000 7100);
DISPLAY 1.212766 (-3000 7100);
PAINT GREEN (-3000 7100);
FORCEPROP 0 LAST CDS_LOCATION R16
J 0
(-3000 7400);
DISPLAY 1.021277 (-3000 7400);
DISPLAY INVISIBLE (-3000 7400);
FORCEPROP 0 LAST $SEC 1
J 0
(-3000 7400);
PAINT MONO (-3000 7400);
DISPLAY INVISIBLE (-3000 7400);
FORCEPROP 0 LAST CDS_SEC 1
J 0
(-3000 7400);
PAINT MONO (-3000 7400);
DISPLAY INVISIBLE (-3000 7400);
FORCEPROP 0 LASTPIN (-3050 7350) $PN 1
R 1
J 0
(-3060 7360);
DISPLAY 0.808511 (-3060 7360);
PAINT MONO (-3060 7360);
FORCEPROP 0 LASTPIN (-3050 7100) $PN 2
R 1
J 2
(-3060 7090);
DISPLAY 0.808511 (-3060 7090);
PAINT MONO (-3060 7090);
FORCEPROP 0 LAST PACKAGE 0402
J 0
(-3000 7450);
DISPLAY 1.021277 (-3000 7450);
FORCEPROP 1 LAST VALUE 3.92KOHM
J 0
(-3000 7300);
DISPLAY 1.212766 (-3000 7300);
PAINT GREEN (-3000 7300);
FORCEPROP 1 LAST CLS_PN G155-03921-01
J 0
(-3186 7450);
DISPLAY 1.212766 (-3186 7450);
PAINT GREEN (-3186 7450);
DISPLAY INVISIBLE (-3186 7450);
FORCEPROP 2 LAST CDS_LIB passive
J 0
(-3050 7250);
DISPLAY INVISIBLE (-3050 7250);
FORCEPROP 1 LAST CDS_LMAN_SYM_OUTLINE -50,50,50,-100
J 0
(-3050 7250);
DISPLAY 0.468085 (-3050 7250);
PAINT GREEN (-3050 7250);
DISPLAY INVISIBLE (-3050 7250);
FORCEPROP 1 LAST TOLERANCE 1%
J 0
(-3247 7505);
DISPLAY 1.212766 (-3247 7505);
PAINT GREEN (-3247 7505);
DISPLAY INVISIBLE (-3247 7505);
FORCEPROP 1 LAST PATH I188
J 0
(-3247 7355);
DISPLAY 1.212766 (-3247 7355);
PAINT GREEN (-3247 7355);
DISPLAY INVISIBLE (-3247 7355);
FORCEADD GND_SG..1
(-5050 7950);
FORCEPROP 3 LASTPIN (-5000 8000) SIG_NAME SG\g
J 0
(-4990 8010);
DISPLAY 0.659574 (-4990 8010);
PAINT MONO (-4990 8010);
DISPLAY INVISIBLE (-4990 8010);
FORCEPROP 1 LAST HDL_POWER SG
J 1
(-4995 7855);
DISPLAY 0.808511 (-4995 7855);
PAINT GREEN (-4995 7855);
FORCEPROP 1 LAST CDS_LMAN_SYM_OUTLINE 0,0,100,-50
J 0
(-5050 7950);
DISPLAY 0.468085 (-5050 7950);
PAINT GREEN (-5050 7950);
DISPLAY INVISIBLE (-5050 7950);
FORCEPROP 2 LAST CDS_LIB cls
J 0
(-5050 7950);
DISPLAY INVISIBLE (-5050 7950);
FORCEPROP 1 LAST BODY_TYPE PLUMBING
J 0
(-5035 7935);
DISPLAY 0.808511 (-5035 7935);
PAINT GREEN (-5035 7935);
DISPLAY INVISIBLE (-5035 7935);
FORCEPROP 1 LAST PATH I195
J 0
(-5015 7950);
DISPLAY 0.808511 (-5015 7950);
PAINT GREEN (-5015 7950);
DISPLAY INVISIBLE (-5015 7950);
FORCEADD CAPACITOR..2
(-5000 8250);
FORCEPROP 1 LAST $LOCATION C6
J 0
(-4950 8100);
DISPLAY 1.212766 (-4950 8100);
PAINT GREEN (-4950 8100);
FORCEPROP 0 LAST CDS_LOCATION C6
J 0
(-4950 8400);
DISPLAY 1.021277 (-4950 8400);
DISPLAY INVISIBLE (-4950 8400);
FORCEPROP 0 LAST $SEC 1
J 0
(-4950 8400);
PAINT MONO (-4950 8400);
DISPLAY INVISIBLE (-4950 8400);
FORCEPROP 0 LAST CDS_SEC 1
J 0
(-4950 8400);
PAINT MONO (-4950 8400);
DISPLAY INVISIBLE (-4950 8400);
FORCEPROP 0 LASTPIN (-5000 8350) $PN 1
R 1
J 0
(-5010 8360);
DISPLAY 0.808511 (-5010 8360);
PAINT MONO (-5010 8360);
FORCEPROP 0 LASTPIN (-5000 8100) $PN 2
R 1
J 2
(-5010 8090);
DISPLAY 0.808511 (-5010 8090);
PAINT MONO (-5010 8090);
FORCEPROP 0 LAST PACKAGE 0402
J 0
(-4900 8200);
DISPLAY 1.021277 (-4900 8200);
FORCEPROP 0 LAST VOLTAGE 25V
J 0
(-4950 8400);
DISPLAY 1.021277 (-4950 8400);
FORCEPROP 1 LAST VALUE 10UF
J 0
(-4950 8300);
DISPLAY 1.212766 (-4950 8300);
PAINT GREEN (-4950 8300);
FORCEPROP 2 LAST CDS_LIB passive
J 0
(-5000 8250);
DISPLAY INVISIBLE (-5000 8250);
FORCEPROP 1 LAST CDS_LMAN_SYM_OUTLINE -50,0,50,-50
J 0
(-5000 8250);
DISPLAY 0.468085 (-5000 8250);
PAINT GREEN (-5000 8250);
DISPLAY INVISIBLE (-5000 8250);
FORCEPROP 1 LAST TOLERANCE 20%
J 0
(-5150 8350);
DISPLAY 1.212766 (-5150 8350);
PAINT GREEN (-5150 8350);
DISPLAY INVISIBLE (-5150 8350);
FORCEPROP 1 LAST CLS_PN G107-0F106-EM
J 0
(-5100 8300);
DISPLAY 1.212766 (-5100 8300);
PAINT GREEN (-5100 8300);
DISPLAY INVISIBLE (-5100 8300);
FORCEPROP 1 LAST PATH I196
J 0
(-5100 8300);
DISPLAY 1.212766 (-5100 8300);
PAINT GREEN (-5100 8300);
DISPLAY INVISIBLE (-5100 8300);
FORCEADD RESISTOR..2
(-4450 8250);
FORCEPROP 1 LAST $LOCATION R12
J 0
(-4400 8100);
DISPLAY 1.212766 (-4400 8100);
PAINT GREEN (-4400 8100);
FORCEPROP 0 LAST CDS_LOCATION R12
J 0
(-4400 8450);
DISPLAY 1.021277 (-4400 8450);
DISPLAY INVISIBLE (-4400 8450);
FORCEPROP 0 LAST $SEC 1
J 0
(-4400 8450);
PAINT MONO (-4400 8450);
DISPLAY INVISIBLE (-4400 8450);
FORCEPROP 0 LAST CDS_SEC 1
J 0
(-4400 8450);
PAINT MONO (-4400 8450);
DISPLAY INVISIBLE (-4400 8450);
FORCEPROP 0 LASTPIN (-4450 8350) $PN 1
R 1
J 0
(-4460 8360);
DISPLAY 0.808511 (-4460 8360);
PAINT MONO (-4460 8360);
FORCEPROP 0 LASTPIN (-4450 8100) $PN 2
R 1
J 2
(-4460 8090);
DISPLAY 0.808511 (-4460 8090);
PAINT MONO (-4460 8090);
FORCEPROP 0 LAST PACKAGE 0402
J 0
(-4400 8250);
DISPLAY 1.021277 (-4400 8250);
FORCEPROP 1 LAST VALUE 10KOHM
J 0
(-4400 8350);
DISPLAY 1.212766 (-4400 8350);
PAINT GREEN (-4400 8350);
FORCEPROP 1 LAST CDS_LMAN_SYM_OUTLINE -50,50,50,-100
J 0
(-4450 8250);
DISPLAY 0.468085 (-4450 8250);
PAINT GREEN (-4450 8250);
DISPLAY INVISIBLE (-4450 8250);
FORCEPROP 2 LAST CDS_LIB passive
J 0
(-4450 8250);
DISPLAY INVISIBLE (-4450 8250);
FORCEPROP 1 LAST CLS_PN G155-11002-01
J 0
(-4586 8450);
DISPLAY 1.212766 (-4586 8450);
PAINT GREEN (-4586 8450);
DISPLAY INVISIBLE (-4586 8450);
FORCEPROP 1 LAST TOLERANCE 1%
J 0
(-4647 8505);
DISPLAY 1.212766 (-4647 8505);
PAINT GREEN (-4647 8505);
DISPLAY INVISIBLE (-4647 8505);
FORCEPROP 1 LAST PATH I197
J 0
(-4647 8355);
DISPLAY 1.212766 (-4647 8355);
PAINT GREEN (-4647 8355);
DISPLAY INVISIBLE (-4647 8355);
FORCEADD RESISTOR..2
(-5000 8800);
FORCEPROP 1 LAST $LOCATION R9
R 1
J 0
(-4900 8750);
DISPLAY 1.212766 (-4900 8750);
PAINT GREEN (-4900 8750);
FORCEPROP 0 LAST CDS_LOCATION R9
J 0
(-4950 8950);
DISPLAY 1.021277 (-4950 8950);
DISPLAY INVISIBLE (-4950 8950);
FORCEPROP 0 LAST $SEC 1
J 0
(-4950 8950);
PAINT MONO (-4950 8950);
DISPLAY INVISIBLE (-4950 8950);
FORCEPROP 0 LAST CDS_SEC 1
J 0
(-4950 8950);
PAINT MONO (-4950 8950);
DISPLAY INVISIBLE (-4950 8950);
FORCEPROP 0 LASTPIN (-5000 8900) $PN 1
R 1
J 0
(-5010 8910);
DISPLAY 0.808511 (-5010 8910);
PAINT MONO (-5010 8910);
FORCEPROP 0 LASTPIN (-5000 8650) $PN 2
R 1
J 2
(-5010 8640);
DISPLAY 0.808511 (-5010 8640);
PAINT MONO (-5010 8640);
FORCEPROP 0 LAST PACKAGE 0603
J 0
(-4950 8650);
DISPLAY 1.021277 (-4950 8650);
FORCEPROP 1 LAST VALUE 49.9OHM
R 1
J 0
(-5050 8550);
DISPLAY 1.212766 (-5050 8550);
PAINT GREEN (-5050 8550);
FORCEPROP 1 LAST CDS_LMAN_SYM_OUTLINE -50,50,50,-100
J 0
(-5000 8800);
DISPLAY 0.468085 (-5000 8800);
PAINT GREEN (-5000 8800);
DISPLAY INVISIBLE (-5000 8800);
FORCEPROP 2 LAST CDS_LIB passive
J 0
(-5000 8800);
DISPLAY INVISIBLE (-5000 8800);
FORCEPROP 1 LAST CLS_PN G156-049R9-01
J 0
(-5136 9000);
DISPLAY 1.212766 (-5136 9000);
PAINT GREEN (-5136 9000);
DISPLAY INVISIBLE (-5136 9000);
FORCEPROP 1 LAST TOLERANCE 1%
J 0
(-5197 9055);
DISPLAY 1.212766 (-5197 9055);
PAINT GREEN (-5197 9055);
DISPLAY INVISIBLE (-5197 9055);
FORCEPROP 1 LAST PATH I198
J 0
(-5197 8905);
DISPLAY 1.212766 (-5197 8905);
PAINT GREEN (-5197 8905);
DISPLAY INVISIBLE (-5197 8905);
FORCEADD RESISTOR..2
(-4450 8750);
FORCEPROP 1 LAST $LOCATION R11
J 0
(-4400 8600);
DISPLAY 1.212766 (-4400 8600);
PAINT GREEN (-4400 8600);
FORCEPROP 0 LAST CDS_LOCATION R11
J 0
(-4400 8900);
DISPLAY 1.021277 (-4400 8900);
DISPLAY INVISIBLE (-4400 8900);
FORCEPROP 0 LAST $SEC 1
J 0
(-4400 8900);
PAINT MONO (-4400 8900);
DISPLAY INVISIBLE (-4400 8900);
FORCEPROP 0 LAST CDS_SEC 1
J 0
(-4400 8900);
PAINT MONO (-4400 8900);
DISPLAY INVISIBLE (-4400 8900);
FORCEPROP 0 LASTPIN (-4450 8850) $PN 1
R 1
J 0
(-4460 8860);
DISPLAY 0.808511 (-4460 8860);
PAINT MONO (-4460 8860);
FORCEPROP 0 LASTPIN (-4450 8600) $PN 2
R 1
J 2
(-4460 8590);
DISPLAY 0.808511 (-4460 8590);
PAINT MONO (-4460 8590);
FORCEPROP 1 LAST VALUE 120KOHM
J 0
(-4400 8800);
DISPLAY 1.212766 (-4400 8800);
PAINT GREEN (-4400 8800);
FORCEPROP 0 LAST PACKAGE 0402
J 0
(-4350 8700);
DISPLAY 1.021277 (-4350 8700);
FORCEPROP 1 LAST CDS_LMAN_SYM_OUTLINE -50,50,50,-100
J 0
(-4450 8750);
DISPLAY 0.468085 (-4450 8750);
PAINT GREEN (-4450 8750);
DISPLAY INVISIBLE (-4450 8750);
FORCEPROP 2 LAST CDS_LIB passive
J 0
(-4450 8750);
DISPLAY INVISIBLE (-4450 8750);
FORCEPROP 1 LAST CLS_PN G155-01203-01
J 0
(-4586 8950);
DISPLAY 1.212766 (-4586 8950);
PAINT GREEN (-4586 8950);
DISPLAY INVISIBLE (-4586 8950);
FORCEPROP 1 LAST TOLERANCE 1%
J 0
(-4647 9005);
DISPLAY 1.212766 (-4647 9005);
PAINT GREEN (-4647 9005);
DISPLAY INVISIBLE (-4647 9005);
FORCEPROP 1 LAST PATH I199
J 0
(-4647 8855);
DISPLAY 1.212766 (-4647 8855);
PAINT GREEN (-4647 8855);
DISPLAY INVISIBLE (-4647 8855);
FORCEADD GND_SG..1
(-4050 7900);
FORCEPROP 3 LASTPIN (-4000 7950) SIG_NAME SG\g
J 0
(-3990 7960);
DISPLAY 0.659574 (-3990 7960);
PAINT MONO (-3990 7960);
DISPLAY INVISIBLE (-3990 7960);
FORCEPROP 1 LAST HDL_POWER SG
J 1
(-3995 7805);
DISPLAY 0.808511 (-3995 7805);
PAINT GREEN (-3995 7805);
FORCEPROP 2 LAST CDS_LIB cls
J 0
(-4050 7900);
DISPLAY INVISIBLE (-4050 7900);
FORCEPROP 1 LAST CDS_LMAN_SYM_OUTLINE 0,0,100,-50
J 0
(-4050 7900);
DISPLAY 0.468085 (-4050 7900);
PAINT GREEN (-4050 7900);
DISPLAY INVISIBLE (-4050 7900);
FORCEPROP 1 LAST BODY_TYPE PLUMBING
J 0
(-4035 7885);
DISPLAY 0.808511 (-4035 7885);
PAINT GREEN (-4035 7885);
DISPLAY INVISIBLE (-4035 7885);
FORCEPROP 1 LAST PATH I200
J 0
(-4015 7900);
DISPLAY 0.808511 (-4015 7900);
PAINT GREEN (-4015 7900);
DISPLAY INVISIBLE (-4015 7900);
FORCEADD CAPACITOR..2
(-4000 8250);
FORCEPROP 1 LAST $LOCATION C8
J 0
(-3950 8100);
DISPLAY 1.212766 (-3950 8100);
PAINT GREEN (-3950 8100);
FORCEPROP 0 LAST CDS_LOCATION C8
J 0
(-3950 8400);
DISPLAY 1.021277 (-3950 8400);
DISPLAY INVISIBLE (-3950 8400);
FORCEPROP 0 LAST $SEC 1
J 0
(-3950 8400);
PAINT MONO (-3950 8400);
DISPLAY INVISIBLE (-3950 8400);
FORCEPROP 0 LAST CDS_SEC 1
J 0
(-3950 8400);
PAINT MONO (-3950 8400);
DISPLAY INVISIBLE (-3950 8400);
FORCEPROP 0 LASTPIN (-4000 8350) $PN 1
R 1
J 0
(-4010 8360);
DISPLAY 0.808511 (-4010 8360);
PAINT MONO (-4010 8360);
FORCEPROP 0 LASTPIN (-4000 8100) $PN 2
R 1
J 2
(-4010 8090);
DISPLAY 0.808511 (-4010 8090);
PAINT MONO (-4010 8090);
FORCEPROP 0 LAST PACKAGE 0402
J 0
(-3900 8200);
DISPLAY 1.021277 (-3900 8200);
FORCEPROP 1 LAST VALUE 0.01UF
J 0
(-3950 8300);
DISPLAY 1.212766 (-3950 8300);
PAINT GREEN (-3950 8300);
FORCEPROP 0 LAST VOLTAGE 25V
J 0
(-3950 8400);
DISPLAY 1.021277 (-3950 8400);
FORCEPROP 1 LAST CDS_LMAN_SYM_OUTLINE -50,0,50,-50
J 0
(-4000 8250);
DISPLAY 0.468085 (-4000 8250);
PAINT GREEN (-4000 8250);
DISPLAY INVISIBLE (-4000 8250);
FORCEPROP 2 LAST CDS_LIB passive
J 0
(-4000 8250);
DISPLAY INVISIBLE (-4000 8250);
FORCEPROP 1 LAST CLS_PN G104-0B103-EK
J 0
(-4100 8300);
DISPLAY 1.212766 (-4100 8300);
PAINT GREEN (-4100 8300);
DISPLAY INVISIBLE (-4100 8300);
FORCEPROP 1 LAST TOLERANCE 10%
J 0
(-4150 8350);
DISPLAY 1.212766 (-4150 8350);
PAINT GREEN (-4150 8350);
DISPLAY INVISIBLE (-4150 8350);
FORCEPROP 1 LAST PATH I201
J 0
(-4100 8300);
DISPLAY 1.212766 (-4100 8300);
PAINT GREEN (-4100 8300);
DISPLAY INVISIBLE (-4100 8300);
FORCEADD RESISTOR..2
(-3600 8050);
FORCEPROP 1 LAST $LOCATION R13
J 0
(-3550 7900);
DISPLAY 1.212766 (-3550 7900);
PAINT GREEN (-3550 7900);
FORCEPROP 0 LAST CDS_LOCATION R13
J 0
(-3550 8200);
DISPLAY 1.021277 (-3550 8200);
DISPLAY INVISIBLE (-3550 8200);
FORCEPROP 0 LAST $SEC 1
J 0
(-3550 8200);
PAINT MONO (-3550 8200);
DISPLAY INVISIBLE (-3550 8200);
FORCEPROP 0 LAST CDS_SEC 1
J 0
(-3550 8200);
PAINT MONO (-3550 8200);
DISPLAY INVISIBLE (-3550 8200);
FORCEPROP 0 LASTPIN (-3600 8150) $PN 1
R 1
J 0
(-3610 8160);
DISPLAY 0.808511 (-3610 8160);
PAINT MONO (-3610 8160);
FORCEPROP 0 LASTPIN (-3600 7900) $PN 2
R 1
J 2
(-3610 7890);
DISPLAY 0.808511 (-3610 7890);
PAINT MONO (-3610 7890);
FORCEPROP 1 LAST VALUE 10KOHM
J 0
(-3550 8100);
DISPLAY 1.212766 (-3550 8100);
PAINT GREEN (-3550 8100);
FORCEPROP 0 LAST PACKAGE 0402
J 0
(-3550 8250);
DISPLAY 1.021277 (-3550 8250);
FORCEPROP 2 LAST CDS_LIB passive
J 0
(-3600 8050);
DISPLAY INVISIBLE (-3600 8050);
FORCEPROP 1 LAST CDS_LMAN_SYM_OUTLINE -50,50,50,-100
J 0
(-3600 8050);
DISPLAY 0.468085 (-3600 8050);
PAINT GREEN (-3600 8050);
DISPLAY INVISIBLE (-3600 8050);
FORCEPROP 1 LAST CLS_PN G155-11002-01
J 0
(-3736 8250);
DISPLAY 1.212766 (-3736 8250);
PAINT GREEN (-3736 8250);
DISPLAY INVISIBLE (-3736 8250);
FORCEPROP 1 LAST TOLERANCE 1%
J 0
(-3797 8305);
DISPLAY 1.212766 (-3797 8305);
PAINT GREEN (-3797 8305);
DISPLAY INVISIBLE (-3797 8305);
FORCEPROP 1 LAST PATH I202
J 0
(-3797 8155);
DISPLAY 1.212766 (-3797 8155);
PAINT GREEN (-3797 8155);
DISPLAY INVISIBLE (-3797 8155);
FORCEADD RESISTOR..2
(-3050 8050);
FORCEPROP 1 LAST $LOCATION R15
J 0
(-3000 7900);
DISPLAY 1.212766 (-3000 7900);
PAINT GREEN (-3000 7900);
FORCEPROP 0 LAST CDS_LOCATION R15
J 0
(-3000 8200);
DISPLAY 1.021277 (-3000 8200);
DISPLAY INVISIBLE (-3000 8200);
FORCEPROP 0 LAST $SEC 1
J 0
(-3000 8200);
PAINT MONO (-3000 8200);
DISPLAY INVISIBLE (-3000 8200);
FORCEPROP 0 LAST CDS_SEC 1
J 0
(-3000 8200);
PAINT MONO (-3000 8200);
DISPLAY INVISIBLE (-3000 8200);
FORCEPROP 0 LASTPIN (-3050 8150) $PN 1
R 1
J 0
(-3060 8160);
DISPLAY 0.808511 (-3060 8160);
PAINT MONO (-3060 8160);
FORCEPROP 0 LASTPIN (-3050 7900) $PN 2
R 1
J 2
(-3060 7890);
DISPLAY 0.808511 (-3060 7890);
PAINT MONO (-3060 7890);
FORCEPROP 1 LAST VALUE 10KOHM
J 0
(-3000 8100);
DISPLAY 1.212766 (-3000 8100);
PAINT GREEN (-3000 8100);
FORCEPROP 0 LAST PACKAGE 0402
J 0
(-3000 8250);
DISPLAY 1.021277 (-3000 8250);
FORCEPROP 1 LAST CDS_LMAN_SYM_OUTLINE -50,50,50,-100
J 0
(-3050 8050);
DISPLAY 0.468085 (-3050 8050);
PAINT GREEN (-3050 8050);
DISPLAY INVISIBLE (-3050 8050);
FORCEPROP 2 LAST CDS_LIB passive
J 0
(-3050 8050);
DISPLAY INVISIBLE (-3050 8050);
FORCEPROP 1 LAST CLS_PN G155-11002-01
J 0
(-3186 8250);
DISPLAY 1.212766 (-3186 8250);
PAINT GREEN (-3186 8250);
DISPLAY INVISIBLE (-3186 8250);
FORCEPROP 1 LAST TOLERANCE 1%
J 0
(-3247 8305);
DISPLAY 1.212766 (-3247 8305);
PAINT GREEN (-3247 8305);
DISPLAY INVISIBLE (-3247 8305);
FORCEPROP 1 LAST PATH I203
J 0
(-3247 8155);
DISPLAY 1.212766 (-3247 8155);
PAINT GREEN (-3247 8155);
DISPLAY INVISIBLE (-3247 8155);
FORCEADD DIODE_2..1
R 1
(-2400 8500);
FORCEPROP 1 LAST $LOCATION CR3
J 2
(-2500 8612);
DISPLAY 1.212766 (-2500 8612);
PAINT GREEN (-2500 8612);
FORCEPROP 0 LAST CDS_LOCATION CR3
R 1
J 0
(-2350 8800);
DISPLAY 1.021277 (-2350 8800);
DISPLAY INVISIBLE (-2350 8800);
FORCEPROP 0 LAST $SEC 1
R 1
J 0
(-2350 8800);
DISPLAY 0.680851 (-2350 8800);
PAINT MONO (-2350 8800);
DISPLAY INVISIBLE (-2350 8800);
FORCEPROP 0 LAST CDS_SEC 1
R 1
J 0
(-2350 8800);
DISPLAY 1.021277 (-2350 8800);
DISPLAY INVISIBLE (-2350 8800);
FORCEPROP 0 LASTPIN (-2400 8250) $PN A
R 1
J 2
(-2410 8240);
DISPLAY 0.680851 (-2410 8240);
PAINT MONO (-2410 8240);
FORCEPROP 0 LASTPIN (-2400 8750) $PN C
R 1
J 0
(-2410 8760);
DISPLAY 0.680851 (-2410 8760);
PAINT MONO (-2410 8760);
FORCEPROP 1 LAST CLS_PN G122-00005-01
R 1
J 0
(-2250 8250);
DISPLAY 1.212766 (-2250 8250);
PAINT GREEN (-2250 8250);
FORCEPROP 0 LAST PART_NUMBER MBRS240LT3G
R 1
J 0
(-2150 8250);
DISPLAY 1.021277 (-2150 8250);
FORCEPROP 1 LAST CDS_LMAN_SYM_OUTLINE -50,50,50,-50
R 1
J 0
(-2400 8500);
DISPLAY 0.468085 (-2400 8500);
PAINT GREEN (-2400 8500);
DISPLAY INVISIBLE (-2400 8500);
FORCEPROP 2 LAST CDS_LIB discrete
J 0
(-2400 8500);
DISPLAY INVISIBLE (-2400 8500);
FORCEPROP 1 LAST PATH I204
R 1
J 0
(-2600 8600);
DISPLAY 1.212766 (-2600 8600);
PAINT GREEN (-2600 8600);
DISPLAY INVISIBLE (-2600 8600);
FORCEADD GND_SG..1
(-1350 8050);
FORCEPROP 3 LASTPIN (-1300 8100) SIG_NAME SG\g
J 0
(-1290 8110);
DISPLAY 0.659574 (-1290 8110);
PAINT MONO (-1290 8110);
DISPLAY INVISIBLE (-1290 8110);
FORCEPROP 1 LAST HDL_POWER SG
J 1
(-1295 7955);
DISPLAY 0.808511 (-1295 7955);
PAINT GREEN (-1295 7955);
FORCEPROP 1 LAST CDS_LMAN_SYM_OUTLINE 0,0,100,-50
J 0
(-1350 8050);
DISPLAY 0.468085 (-1350 8050);
PAINT GREEN (-1350 8050);
DISPLAY INVISIBLE (-1350 8050);
FORCEPROP 2 LAST CDS_LIB cls
J 0
(-1350 8050);
DISPLAY INVISIBLE (-1350 8050);
FORCEPROP 1 LAST BODY_TYPE PLUMBING
J 0
(-1335 8035);
DISPLAY 0.808511 (-1335 8035);
PAINT GREEN (-1335 8035);
DISPLAY INVISIBLE (-1335 8035);
FORCEPROP 1 LAST PATH I205
J 0
(-1315 8050);
DISPLAY 0.808511 (-1315 8050);
PAINT GREEN (-1315 8050);
DISPLAY INVISIBLE (-1315 8050);
FORCEADD CAPACITOR..2
(-1800 8650);
FORCEPROP 1 LAST $LOCATION C9
J 0
(-1750 8500);
DISPLAY 1.212766 (-1750 8500);
PAINT GREEN (-1750 8500);
FORCEPROP 0 LAST CDS_LOCATION C9
J 0
(-1750 8800);
DISPLAY 1.021277 (-1750 8800);
DISPLAY INVISIBLE (-1750 8800);
FORCEPROP 0 LAST $SEC 1
J 0
(-1750 8800);
DISPLAY 0.680851 (-1750 8800);
PAINT MONO (-1750 8800);
DISPLAY INVISIBLE (-1750 8800);
FORCEPROP 0 LAST CDS_SEC 1
J 0
(-1750 8800);
DISPLAY 1.021277 (-1750 8800);
DISPLAY INVISIBLE (-1750 8800);
FORCEPROP 0 LASTPIN (-1800 8750) $PN 1
R 1
J 0
(-1810 8760);
DISPLAY 0.680851 (-1810 8760);
PAINT MONO (-1810 8760);
FORCEPROP 0 LASTPIN (-1800 8500) $PN 2
R 1
J 2
(-1810 8490);
DISPLAY 0.680851 (-1810 8490);
PAINT MONO (-1810 8490);
FORCEPROP 1 LAST VALUE 10UF
J 0
(-1750 8700);
DISPLAY 1.212766 (-1750 8700);
PAINT GREEN (-1750 8700);
FORCEPROP 0 LAST VOLTAGE 25V
J 0
(-1750 8900);
DISPLAY 1.021277 (-1750 8900);
FORCEPROP 0 LAST PACKAGE 0805
J 0
(-1750 8800);
DISPLAY 1.021277 (-1750 8800);
FORCEPROP 1 LAST CLS_PN G107-0F106-EM
J 0
(-1900 8700);
DISPLAY 1.212766 (-1900 8700);
PAINT GREEN (-1900 8700);
DISPLAY INVISIBLE (-1900 8700);
FORCEPROP 1 LAST TOLERANCE 20%
J 0
(-1950 8750);
DISPLAY 1.212766 (-1950 8750);
PAINT GREEN (-1950 8750);
DISPLAY INVISIBLE (-1950 8750);
FORCEPROP 1 LAST CDS_LMAN_SYM_OUTLINE -50,0,50,-50
J 0
(-1800 8650);
DISPLAY 0.468085 (-1800 8650);
PAINT GREEN (-1800 8650);
DISPLAY INVISIBLE (-1800 8650);
FORCEPROP 2 LAST CDS_LIB passive
J 0
(-1800 8650);
DISPLAY INVISIBLE (-1800 8650);
FORCEPROP 1 LAST PATH I206
J 0
(-1900 8700);
DISPLAY 1.212766 (-1900 8700);
PAINT GREEN (-1900 8700);
DISPLAY INVISIBLE (-1900 8700);
FORCEADD CAPACITOR..2
(-1300 8650);
FORCEPROP 1 LAST $LOCATION C10
J 0
(-1150 8500);
DISPLAY 1.212766 (-1150 8500);
PAINT GREEN (-1150 8500);
FORCEPROP 0 LAST CDS_LOCATION C10
J 0
(-1200 8900);
DISPLAY 1.021277 (-1200 8900);
DISPLAY INVISIBLE (-1200 8900);
FORCEPROP 0 LAST $SEC 1
J 0
(-1200 8900);
DISPLAY 0.680851 (-1200 8900);
PAINT MONO (-1200 8900);
DISPLAY INVISIBLE (-1200 8900);
FORCEPROP 0 LAST CDS_SEC 1
J 0
(-1200 8900);
DISPLAY 1.021277 (-1200 8900);
DISPLAY INVISIBLE (-1200 8900);
FORCEPROP 0 LASTPIN (-1300 8750) $PN 1
R 1
J 0
(-1310 8760);
DISPLAY 0.680851 (-1310 8760);
PAINT MONO (-1310 8760);
FORCEPROP 0 LASTPIN (-1300 8500) $PN 2
R 1
J 2
(-1310 8490);
DISPLAY 0.680851 (-1310 8490);
PAINT MONO (-1310 8490);
FORCEPROP 1 LAST VALUE 10UF
J 0
(-1200 8700);
DISPLAY 1.212766 (-1200 8700);
PAINT GREEN (-1200 8700);
FORCEPROP 0 LAST VOLTAGE 25V
J 0
(-1200 8900);
DISPLAY 1.021277 (-1200 8900);
FORCEPROP 0 LAST PACKAGE 0805
J 0
(-1200 8800);
DISPLAY 1.021277 (-1200 8800);
FORCEPROP 2 LAST CDS_LIB passive
J 0
(-1300 8650);
DISPLAY INVISIBLE (-1300 8650);
FORCEPROP 1 LAST CDS_LMAN_SYM_OUTLINE -50,0,50,-50
J 0
(-1300 8650);
DISPLAY 0.468085 (-1300 8650);
PAINT GREEN (-1300 8650);
DISPLAY INVISIBLE (-1300 8650);
FORCEPROP 1 LAST TOLERANCE 20%
J 0
(-1450 8750);
DISPLAY 1.212766 (-1450 8750);
PAINT GREEN (-1450 8750);
DISPLAY INVISIBLE (-1450 8750);
FORCEPROP 1 LAST CLS_PN G107-0F106-EM
J 0
(-1400 8700);
DISPLAY 1.212766 (-1400 8700);
PAINT GREEN (-1400 8700);
DISPLAY INVISIBLE (-1400 8700);
FORCEPROP 1 LAST PATH I207
J 0
(-1400 8700);
DISPLAY 1.212766 (-1400 8700);
PAINT GREEN (-1400 8700);
DISPLAY INVISIBLE (-1400 8700);
FORCEADD VCC..1
(-900 9400);
FORCEPROP 3 LASTPIN (-850 9350) SIG_NAME XP12R0V\g
J 0
(-840 9360);
DISPLAY 0.659574 (-840 9360);
PAINT MONO (-840 9360);
DISPLAY INVISIBLE (-840 9360);
FORCEPROP 0 LAST VOLTAGE 12V
J 0
(-1100 9500);
DISPLAY 1.021277 (-1100 9500);
DISPLAY BOTH (-1100 9500);
FORCEPROP 1 LAST HDL_POWER XP12R0V
J 1
(-845 9455);
DISPLAY 0.808511 (-845 9455);
PAINT GREEN (-845 9455);
FORCEPROP 1 LAST PATH I209
J 0
(-865 9490);
DISPLAY 0.808511 (-865 9490);
PAINT GREEN (-865 9490);
DISPLAY INVISIBLE (-865 9490);
FORCEPROP 1 LAST BODY_TYPE PLUMBING
J 0
(-945 9357);
DISPLAY 0.340426 (-945 9357);
PAINT GREEN (-945 9357);
DISPLAY INVISIBLE (-945 9357);
FORCEPROP 1 LAST CDS_LMAN_SYM_OUTLINE -250,250,250,-250
J 0
(-900 9400);
DISPLAY 0.468085 (-900 9400);
PAINT GREEN (-900 9400);
DISPLAY INVISIBLE (-900 9400);
FORCEPROP 2 LAST CDS_LIB cls
J 0
(-900 9400);
DISPLAY INVISIBLE (-900 9400);
FORCEADD CAPACITOR..2
(-5200 6900);
FORCEPROP 1 LAST $LOCATION C5
J 0
(-5100 6700);
DISPLAY 1.212766 (-5100 6700);
PAINT GREEN (-5100 6700);
FORCEPROP 0 LAST CDS_LOCATION C5
J 0
(-5150 7050);
DISPLAY 1.021277 (-5150 7050);
DISPLAY INVISIBLE (-5150 7050);
FORCEPROP 0 LAST $SEC 1
J 0
(-5150 7050);
PAINT MONO (-5150 7050);
DISPLAY INVISIBLE (-5150 7050);
FORCEPROP 0 LAST CDS_SEC 1
J 0
(-5150 7050);
PAINT MONO (-5150 7050);
DISPLAY INVISIBLE (-5150 7050);
FORCEPROP 0 LASTPIN (-5200 7000) $PN 1
R 1
J 0
(-5210 7010);
DISPLAY 0.808511 (-5210 7010);
PAINT MONO (-5210 7010);
FORCEPROP 0 LASTPIN (-5200 6750) $PN 2
R 1
J 2
(-5210 6740);
DISPLAY 0.808511 (-5210 6740);
PAINT MONO (-5210 6740);
FORCEPROP 0 LAST VOLTAGE 25V
J 0
(-5100 7000);
DISPLAY 1.021277 (-5100 7000);
FORCEPROP 0 LAST PACKAGE 0402
J 0
(-5050 6800);
DISPLAY 1.021277 (-5050 6800);
FORCEPROP 1 LAST VALUE 0.1UF
J 0
(-5100 6900);
DISPLAY 1.212766 (-5100 6900);
PAINT GREEN (-5100 6900);
FORCEPROP 1 LAST PATH I211
J 0
(-5300 6950);
DISPLAY 1.212766 (-5300 6950);
PAINT GREEN (-5300 6950);
DISPLAY INVISIBLE (-5300 6950);
FORCEPROP 1 LAST CLS_PN G105-0B104-EK
J 0
(-5300 6950);
DISPLAY 1.212766 (-5300 6950);
PAINT GREEN (-5300 6950);
DISPLAY INVISIBLE (-5300 6950);
FORCEPROP 1 LAST TOLERANCE 10%
J 0
(-5350 7000);
DISPLAY 1.212766 (-5350 7000);
PAINT GREEN (-5350 7000);
DISPLAY INVISIBLE (-5350 7000);
FORCEPROP 2 LAST CDS_LIB passive
J 0
(-5200 6900);
DISPLAY INVISIBLE (-5200 6900);
FORCEPROP 1 LAST CDS_LMAN_SYM_OUTLINE -50,0,50,-50
J 0
(-5200 6900);
DISPLAY 0.468085 (-5200 6900);
PAINT GREEN (-5200 6900);
DISPLAY INVISIBLE (-5200 6900);
FORCEADD MP5022CGQV_Z_QFN22..1
(-6650 9100);
FORCEPROP 1 LAST $LOCATION U1
J 0
(-6600 9200);
DISPLAY 1.212766 (-6600 9200);
PAINT GREEN (-6600 9200);
FORCEPROP 0 LAST CDS_LOCATION U1
J 0
(-6600 9500);
DISPLAY 1.021277 (-6600 9500);
DISPLAY INVISIBLE (-6600 9500);
FORCEPROP 0 LAST $SEC 1
J 0
(-6600 9400);
PAINT MONO (-6600 9400);
DISPLAY INVISIBLE (-6600 9400);
FORCEPROP 0 LAST CDS_SEC 1
J 0
(-6600 9400);
PAINT MONO (-6600 9400);
DISPLAY INVISIBLE (-6600 9400);
FORCEPROP 2 LASTPIN (-5550 8100) $PN 12
J 0
(-5540 8110);
DISPLAY 0.680851 (-5540 8110);
PAINT MONO (-5540 8110);
FORCEPROP 2 LASTPIN (-6750 8300) $PN 1
J 2
(-6760 8310);
DISPLAY 0.680851 (-6760 8310);
PAINT MONO (-6760 8310);
FORCEPROP 2 LASTPIN (-6750 7900) $PN 3
J 2
(-6760 7910);
DISPLAY 0.680851 (-6760 7910);
PAINT MONO (-6760 7910);
FORCEPROP 2 LASTPIN (-5550 7500) $PN 9
J 0
(-5540 7510);
DISPLAY 0.680851 (-5540 7510);
PAINT MONO (-5540 7510);
FORCEPROP 2 LASTPIN (-5550 6900) $PN 7
J 0
(-5540 6910);
DISPLAY 0.680851 (-5540 6910);
PAINT MONO (-5540 6910);
FORCEPROP 2 LASTPIN (-5550 7300) $PN 8
J 0
(-5540 7310);
DISPLAY 0.680851 (-5540 7310);
PAINT MONO (-5540 7310);
FORCEPROP 2 LASTPIN (-6750 7500) $PN 5
J 2
(-6760 7510);
DISPLAY 0.680851 (-6760 7510);
PAINT MONO (-6760 7510);
FORCEPROP 2 LASTPIN (-6750 8100) $PN 2
J 2
(-6760 8110);
DISPLAY 0.680851 (-6760 8110);
PAINT MONO (-6760 8110);
FORCEPROP 2 LASTPIN (-5550 7900) $PN 11
J 0
(-5540 7910);
DISPLAY 0.680851 (-5540 7910);
PAINT MONO (-5540 7910);
FORCEPROP 2 LASTPIN (-5550 7700) $PN 10
J 0
(-5540 7710);
DISPLAY 0.680851 (-5540 7710);
PAINT MONO (-5540 7710);
FORCEPROP 2 LASTPIN (-5550 7100) $PN 6
J 0
(-5540 7110);
DISPLAY 0.680851 (-5540 7110);
PAINT MONO (-5540 7110);
FORCEPROP 2 LASTPIN (-6750 7700) $PN 4
J 2
(-6760 7710);
DISPLAY 0.680851 (-6760 7710);
PAINT MONO (-6760 7710);
FORCEPROP 2 LASTPIN (-6750 9000) $PN 21
J 2
(-6760 9010);
DISPLAY 0.680851 (-6760 9010);
PAINT MONO (-6760 9010);
FORCEPROP 2 LASTPIN (-6750 8900) $PN 22
J 2
(-6760 8910);
DISPLAY 0.680851 (-6760 8910);
PAINT MONO (-6760 8910);
FORCEPROP 2 LASTPIN (-6750 8800) $PN 23
J 2
(-6760 8810);
DISPLAY 0.680851 (-6760 8810);
PAINT MONO (-6760 8810);
FORCEPROP 2 LASTPIN (-6750 8700) $PN 24
J 2
(-6760 8710);
DISPLAY 0.680851 (-6760 8710);
PAINT MONO (-6760 8710);
FORCEPROP 2 LASTPIN (-6750 8600) $PN 25
J 2
(-6760 8610);
DISPLAY 0.680851 (-6760 8610);
PAINT MONO (-6760 8610);
FORCEPROP 2 LASTPIN (-6750 8500) $PN 26
J 2
(-6760 8510);
DISPLAY 0.680851 (-6760 8510);
PAINT MONO (-6760 8510);
FORCEPROP 2 LASTPIN (-5550 9000) $PN 13
J 0
(-5540 9010);
DISPLAY 0.680851 (-5540 9010);
PAINT MONO (-5540 9010);
FORCEPROP 2 LASTPIN (-5550 8900) $PN 14
J 0
(-5540 8910);
DISPLAY 0.680851 (-5540 8910);
PAINT MONO (-5540 8910);
FORCEPROP 2 LASTPIN (-5550 8800) $PN 15
J 0
(-5540 8810);
DISPLAY 0.680851 (-5540 8810);
PAINT MONO (-5540 8810);
FORCEPROP 2 LASTPIN (-5550 8700) $PN 16
J 0
(-5540 8710);
DISPLAY 0.680851 (-5540 8710);
PAINT MONO (-5540 8710);
FORCEPROP 2 LASTPIN (-5550 8600) $PN 17
J 0
(-5540 8610);
DISPLAY 0.680851 (-5540 8610);
PAINT MONO (-5540 8610);
FORCEPROP 2 LASTPIN (-5550 8500) $PN 18
J 0
(-5540 8510);
DISPLAY 0.680851 (-5540 8510);
PAINT MONO (-5540 8510);
FORCEPROP 2 LASTPIN (-5550 8400) $PN 19
J 0
(-5540 8410);
DISPLAY 0.680851 (-5540 8410);
PAINT MONO (-5540 8410);
FORCEPROP 2 LASTPIN (-5550 8300) $PN 20
J 0
(-5540 8310);
DISPLAY 0.680851 (-5540 8310);
PAINT MONO (-5540 8310);
FORCEPROP 1 LAST CLS_PN G220-10510-01
J 0
(-6600 9300);
DISPLAY 1.212766 (-6600 9300);
PAINT GREEN (-6600 9300);
FORCEPROP 0 LAST PART_NUMBER MP5022CGQV-Z
J 0
(-6200 9200);
DISPLAY 1.021277 (-6200 9200);
FORCEPROP 1 LAST CDS_LMAN_SYM_OUTLINE 0,0,1000,-2300
J 0
(-6650 9100);
DISPLAY 0.468085 (-6650 9100);
PAINT GREEN (-6650 9100);
DISPLAY INVISIBLE (-6650 9100);
FORCEPROP 2 LAST CDS_LIB stdlogic
J 0
(-6650 9100);
DISPLAY INVISIBLE (-6650 9100);
FORCEPROP 2 LASTPIN (-6750 7900) SIG_NAME UN$15$MP5022CGQVZQFN22$I212$ENTM
J 0
(-6740 7910);
DISPLAY 0.659574 (-6740 7910);
PAINT MONO (-6740 7910);
DISPLAY INVISIBLE (-6740 7910);
FORCEPROP 2 LASTPIN (-6750 8100) SIG_NAME UN$15$MP5022CGQVZQFN22$I212$LOADEN
J 0
(-6740 8110);
DISPLAY 0.659574 (-6740 8110);
PAINT MONO (-6740 8110);
DISPLAY INVISIBLE (-6740 8110);
FORCEPROP 1 LAST PATH I212
J 0
(-6600 9150);
DISPLAY 1.212766 (-6600 9150);
PAINT GREEN (-6600 9150);
DISPLAY INVISIBLE (-6600 9150);
FORCEADD VCC..1
(-13300 9800);
FORCEPROP 3 LASTPIN (-13250 9750) SIG_NAME XP12R0V_EXT\g
J 0
(-13240 9760);
DISPLAY 0.659574 (-13240 9760);
PAINT MONO (-13240 9760);
DISPLAY INVISIBLE (-13240 9760);
FORCEPROP 1 LAST HDL_POWER XP12R0V_EXT
J 1
(-13250 9850);
DISPLAY 0.808511 (-13250 9850);
PAINT GREEN (-13250 9850);
FORCEPROP 0 LAST VOLTAGE 12
J 1
(-13250 9900);
DISPLAY 1.021277 (-13250 9900);
DISPLAY BOTH (-13250 9900);
FORCEPROP 1 LAST PATH I213
J 0
(-13265 9890);
DISPLAY 0.808511 (-13265 9890);
PAINT GREEN (-13265 9890);
DISPLAY INVISIBLE (-13265 9890);
FORCEPROP 1 LAST BODY_TYPE PLUMBING
J 0
(-13345 9757);
DISPLAY 0.340426 (-13345 9757);
PAINT GREEN (-13345 9757);
DISPLAY INVISIBLE (-13345 9757);
FORCEPROP 1 LAST CDS_LMAN_SYM_OUTLINE -250,250,250,-250
J 0
(-13300 9800);
DISPLAY 0.468085 (-13300 9800);
PAINT GREEN (-13300 9800);
DISPLAY INVISIBLE (-13300 9800);
FORCEPROP 2 LAST CDS_LIB cls
J 0
(-13300 9800);
DISPLAY INVISIBLE (-13300 9800);
FORCEADD VCC..1
(-12650 9800);
FORCEPROP 3 LASTPIN (-12600 9750) SIG_NAME XP12R0V_PCIE\g
J 0
(-12590 9760);
DISPLAY 0.659574 (-12590 9760);
PAINT MONO (-12590 9760);
DISPLAY INVISIBLE (-12590 9760);
FORCEPROP 0 LAST VOLTAGE 12
J 1
(-12600 9900);
DISPLAY 1.021277 (-12600 9900);
DISPLAY BOTH (-12600 9900);
FORCEPROP 1 LAST HDL_POWER XP12R0V_PCIE
J 1
(-12600 9850);
DISPLAY 0.808511 (-12600 9850);
PAINT GREEN (-12600 9850);
FORCEPROP 1 LAST BODY_TYPE PLUMBING
J 0
(-12695 9757);
DISPLAY 0.340426 (-12695 9757);
PAINT GREEN (-12695 9757);
DISPLAY INVISIBLE (-12695 9757);
FORCEPROP 1 LAST PATH I215
J 0
(-12615 9890);
DISPLAY 0.808511 (-12615 9890);
PAINT GREEN (-12615 9890);
DISPLAY INVISIBLE (-12615 9890);
FORCEPROP 1 LAST CDS_LMAN_SYM_OUTLINE -250,250,250,-250
J 0
(-12650 9800);
DISPLAY 0.468085 (-12650 9800);
PAINT GREEN (-12650 9800);
DISPLAY INVISIBLE (-12650 9800);
FORCEPROP 2 LAST CDS_LIB cls
J 0
(-12650 9800);
DISPLAY INVISIBLE (-12650 9800);
FORCEADD FUSE..1
(-3500 9400);
FORCEPROP 1 LAST $LOCATION FU1
J 2
(-3632 9450);
DISPLAY 1.212766 (-3632 9450);
PAINT GREEN (-3632 9450);
FORCEPROP 0 LAST CDS_LOCATION FU1
J 0
(-3300 9550);
DISPLAY 1.021277 (-3300 9550);
DISPLAY INVISIBLE (-3300 9550);
FORCEPROP 0 LAST $SEC 1
J 0
(-3300 9550);
DISPLAY 0.680851 (-3300 9550);
PAINT MONO (-3300 9550);
DISPLAY INVISIBLE (-3300 9550);
FORCEPROP 0 LAST CDS_SEC 1
J 0
(-3300 9550);
DISPLAY 1.021277 (-3300 9550);
DISPLAY INVISIBLE (-3300 9550);
FORCEPROP 0 LASTPIN (-3650 9400) $PN 1
J 2
(-3660 9410);
DISPLAY 0.680851 (-3660 9410);
PAINT MONO (-3660 9410);
FORCEPROP 0 LASTPIN (-3300 9400) $PN 2
J 0
(-3290 9410);
DISPLAY 0.680851 (-3290 9410);
PAINT MONO (-3290 9410);
FORCEPROP 0 LAST PACKAGE 0603
J 0
(-3550 9450);
DISPLAY 1.021277 (-3550 9450);
FORCEPROP 1 LAST VALUE 2.5A
J 0
(-3300 9450);
DISPLAY 1.212766 (-3300 9450);
PAINT GREEN (-3300 9450);
FORCEPROP 0 LAST NO_ASSY TRUE
J 0
(-3700 9300);
DISPLAY 1.021277 (-3700 9300);
DISPLAY BOTH (-3700 9300);
FORCEPROP 2 LAST CDS_LIB passive
J 0
(-3500 9400);
DISPLAY INVISIBLE (-3500 9400);
FORCEPROP 1 LAST CDS_LMAN_SYM_OUTLINE -50,50,100,-50
J 0
(-3500 9400);
DISPLAY 0.468085 (-3500 9400);
PAINT GREEN (-3500 9400);
DISPLAY INVISIBLE (-3500 9400);
FORCEPROP 1 LAST CLS_PN G280-10012-01
J 0
(-3350 9500);
DISPLAY 1.212766 (-3350 9500);
PAINT GREEN (-3350 9500);
DISPLAY INVISIBLE (-3350 9500);
FORCEPROP 1 LAST PATH I223
J 2
(-3600 9500);
DISPLAY 1.212766 (-3600 9500);
PAINT GREEN (-3600 9500);
DISPLAY INVISIBLE (-3600 9500);
FORCEADD GND_SG..1
(-12300 7950);
FORCEPROP 3 LASTPIN (-12250 8000) SIG_NAME SG\g
J 0
(-12240 8010);
DISPLAY 0.659574 (-12240 8010);
PAINT MONO (-12240 8010);
DISPLAY INVISIBLE (-12240 8010);
FORCEPROP 1 LAST HDL_POWER SG
J 1
(-12245 7855);
DISPLAY 0.808511 (-12245 7855);
PAINT GREEN (-12245 7855);
FORCEPROP 2 LAST CDS_LIB cls
J 0
(-12300 7950);
DISPLAY INVISIBLE (-12300 7950);
FORCEPROP 1 LAST CDS_LMAN_SYM_OUTLINE 0,0,100,-50
J 0
(-12300 7950);
DISPLAY 0.468085 (-12300 7950);
PAINT GREEN (-12300 7950);
DISPLAY INVISIBLE (-12300 7950);
FORCEPROP 1 LAST BODY_TYPE PLUMBING
J 0
(-12285 7935);
DISPLAY 0.808511 (-12285 7935);
PAINT GREEN (-12285 7935);
DISPLAY INVISIBLE (-12285 7935);
FORCEPROP 1 LAST PATH I226
J 0
(-12265 7950);
DISPLAY 0.808511 (-12265 7950);
PAINT GREEN (-12265 7950);
DISPLAY INVISIBLE (-12265 7950);
FORCEADD CAPACITOR..2
(-10650 9000);
FORCEPROP 1 LAST $LOCATION C297
J 0
(-10550 8950);
DISPLAY 1.212766 (-10550 8950);
PAINT GREEN (-10550 8950);
FORCEPROP 0 LAST CDS_LOCATION C297
J 0
(-10600 9250);
DISPLAY 1.021277 (-10600 9250);
DISPLAY INVISIBLE (-10600 9250);
FORCEPROP 0 LAST $SEC 1
J 0
(-10600 9250);
DISPLAY 0.680851 (-10600 9250);
PAINT MONO (-10600 9250);
DISPLAY INVISIBLE (-10600 9250);
FORCEPROP 0 LAST CDS_SEC 1
J 0
(-10600 9250);
DISPLAY 1.021277 (-10600 9250);
DISPLAY INVISIBLE (-10600 9250);
FORCEPROP 0 LASTPIN (-10650 9100) $PN 1
R 1
J 0
(-10660 9110);
DISPLAY 0.680851 (-10660 9110);
PAINT MONO (-10660 9110);
FORCEPROP 0 LASTPIN (-10650 8850) $PN 2
R 1
J 2
(-10660 8840);
DISPLAY 0.680851 (-10660 8840);
PAINT MONO (-10660 8840);
FORCEPROP 0 LAST PACKAGE 0805
J 0
(-10600 9200);
DISPLAY 1.021277 (-10600 9200);
FORCEPROP 1 LAST VALUE 10UF
J 0
(-10550 9050);
DISPLAY 1.212766 (-10550 9050);
PAINT GREEN (-10550 9050);
FORCEPROP 0 LAST VOLTAGE 25V
J 0
(-10600 9300);
DISPLAY 1.021277 (-10600 9300);
FORCEPROP 0 LAST NO_ASSY TRUE
J 0
(-10600 8850);
DISPLAY 0.808511 (-10600 8850);
DISPLAY BOTH (-10600 8850);
FORCEPROP 1 LAST TOLERANCE 20%
J 0
(-10800 9100);
DISPLAY 1.212766 (-10800 9100);
PAINT GREEN (-10800 9100);
DISPLAY INVISIBLE (-10800 9100);
FORCEPROP 1 LAST CLS_PN G107-0F106-EM
J 0
(-10750 9050);
DISPLAY 1.212766 (-10750 9050);
PAINT GREEN (-10750 9050);
DISPLAY INVISIBLE (-10750 9050);
FORCEPROP 1 LAST CDS_LMAN_SYM_OUTLINE -50,0,50,-50
J 0
(-10650 9000);
DISPLAY 0.468085 (-10650 9000);
PAINT GREEN (-10650 9000);
DISPLAY INVISIBLE (-10650 9000);
FORCEPROP 2 LAST CDS_LIB passive
J 0
(-10650 9000);
DISPLAY INVISIBLE (-10650 9000);
FORCEPROP 1 LAST PATH I229
J 0
(-10750 9050);
DISPLAY 1.212766 (-10750 9050);
PAINT GREEN (-10750 9050);
DISPLAY INVISIBLE (-10750 9050);
FORCEADD CAPACITOR..2
(-10250 9000);
FORCEPROP 1 LAST $LOCATION C299
J 0
(-10150 8950);
DISPLAY 1.212766 (-10150 8950);
PAINT GREEN (-10150 8950);
FORCEPROP 0 LAST CDS_LOCATION C299
J 0
(-10200 9250);
DISPLAY 1.021277 (-10200 9250);
DISPLAY INVISIBLE (-10200 9250);
FORCEPROP 0 LAST $SEC 1
J 0
(-10200 9250);
DISPLAY 0.680851 (-10200 9250);
PAINT MONO (-10200 9250);
DISPLAY INVISIBLE (-10200 9250);
FORCEPROP 0 LAST CDS_SEC 1
J 0
(-10200 9250);
DISPLAY 1.021277 (-10200 9250);
DISPLAY INVISIBLE (-10200 9250);
FORCEPROP 0 LASTPIN (-10250 9100) $PN 1
R 1
J 0
(-10260 9110);
DISPLAY 0.680851 (-10260 9110);
PAINT MONO (-10260 9110);
FORCEPROP 0 LASTPIN (-10250 8850) $PN 2
R 1
J 2
(-10260 8840);
DISPLAY 0.680851 (-10260 8840);
PAINT MONO (-10260 8840);
FORCEPROP 0 LAST VOLTAGE 25V
J 0
(-10200 9300);
DISPLAY 1.021277 (-10200 9300);
FORCEPROP 1 LAST VALUE 10UF
J 0
(-10150 9050);
DISPLAY 1.212766 (-10150 9050);
PAINT GREEN (-10150 9050);
FORCEPROP 0 LAST NO_ASSY TRUE
J 0
(-10200 8900);
DISPLAY 0.808511 (-10200 8900);
DISPLAY BOTH (-10200 8900);
FORCEPROP 0 LAST PACKAGE 0805
J 0
(-10200 9200);
DISPLAY 1.021277 (-10200 9200);
FORCEPROP 1 LAST TOLERANCE 20%
J 0
(-10400 9100);
DISPLAY 1.212766 (-10400 9100);
PAINT GREEN (-10400 9100);
DISPLAY INVISIBLE (-10400 9100);
FORCEPROP 1 LAST CLS_PN G107-0F106-EM
J 0
(-10350 9050);
DISPLAY 1.212766 (-10350 9050);
PAINT GREEN (-10350 9050);
DISPLAY INVISIBLE (-10350 9050);
FORCEPROP 1 LAST CDS_LMAN_SYM_OUTLINE -50,0,50,-50
J 0
(-10250 9000);
DISPLAY 0.468085 (-10250 9000);
PAINT GREEN (-10250 9000);
DISPLAY INVISIBLE (-10250 9000);
FORCEPROP 2 LAST CDS_LIB passive
J 0
(-10250 9000);
DISPLAY INVISIBLE (-10250 9000);
FORCEPROP 1 LAST PATH I230
J 0
(-10350 9050);
DISPLAY 1.212766 (-10350 9050);
PAINT GREEN (-10350 9050);
DISPLAY INVISIBLE (-10350 9050);
FORCEADD CAPACITOR..2
(-9450 9000);
FORCEPROP 1 LAST $LOCATION C303
J 0
(-9350 8950);
DISPLAY 1.212766 (-9350 8950);
PAINT GREEN (-9350 8950);
FORCEPROP 0 LAST CDS_LOCATION C303
J 0
(-9400 9250);
DISPLAY 1.021277 (-9400 9250);
DISPLAY INVISIBLE (-9400 9250);
FORCEPROP 0 LAST $SEC 1
J 0
(-9400 9250);
DISPLAY 0.680851 (-9400 9250);
PAINT MONO (-9400 9250);
DISPLAY INVISIBLE (-9400 9250);
FORCEPROP 0 LAST CDS_SEC 1
J 0
(-9400 9250);
DISPLAY 1.021277 (-9400 9250);
DISPLAY INVISIBLE (-9400 9250);
FORCEPROP 0 LASTPIN (-9450 9100) $PN 1
R 1
J 0
(-9460 9110);
DISPLAY 0.680851 (-9460 9110);
PAINT MONO (-9460 9110);
FORCEPROP 0 LASTPIN (-9450 8850) $PN 2
R 1
J 2
(-9460 8840);
DISPLAY 0.680851 (-9460 8840);
PAINT MONO (-9460 8840);
FORCEPROP 0 LAST VOLTAGE 25V
J 0
(-9400 9300);
DISPLAY 1.021277 (-9400 9300);
FORCEPROP 1 LAST VALUE 10UF
J 0
(-9350 9050);
DISPLAY 1.212766 (-9350 9050);
PAINT GREEN (-9350 9050);
FORCEPROP 0 LAST NO_ASSY TRUE
J 0
(-9400 8900);
DISPLAY 0.808511 (-9400 8900);
DISPLAY BOTH (-9400 8900);
FORCEPROP 0 LAST PACKAGE 0805
J 0
(-9400 9200);
DISPLAY 1.021277 (-9400 9200);
FORCEPROP 1 LAST TOLERANCE 20%
J 0
(-9600 9100);
DISPLAY 1.212766 (-9600 9100);
PAINT GREEN (-9600 9100);
DISPLAY INVISIBLE (-9600 9100);
FORCEPROP 1 LAST CLS_PN G107-0F106-EM
J 0
(-9550 9050);
DISPLAY 1.212766 (-9550 9050);
PAINT GREEN (-9550 9050);
DISPLAY INVISIBLE (-9550 9050);
FORCEPROP 1 LAST CDS_LMAN_SYM_OUTLINE -50,0,50,-50
J 0
(-9450 9000);
DISPLAY 0.468085 (-9450 9000);
PAINT GREEN (-9450 9000);
DISPLAY INVISIBLE (-9450 9000);
FORCEPROP 2 LAST CDS_LIB passive
J 0
(-9450 9000);
DISPLAY INVISIBLE (-9450 9000);
FORCEPROP 1 LAST PATH I231
J 0
(-9550 9050);
DISPLAY 1.212766 (-9550 9050);
PAINT GREEN (-9550 9050);
DISPLAY INVISIBLE (-9550 9050);
FORCEADD CAPACITOR..2
(-9850 9000);
FORCEPROP 1 LAST $LOCATION C301
J 0
(-9750 8950);
DISPLAY 1.212766 (-9750 8950);
PAINT GREEN (-9750 8950);
FORCEPROP 0 LAST CDS_LOCATION C301
J 0
(-9800 9250);
DISPLAY 1.021277 (-9800 9250);
DISPLAY INVISIBLE (-9800 9250);
FORCEPROP 0 LAST $SEC 1
J 0
(-9800 9250);
DISPLAY 0.680851 (-9800 9250);
PAINT MONO (-9800 9250);
DISPLAY INVISIBLE (-9800 9250);
FORCEPROP 0 LAST CDS_SEC 1
J 0
(-9800 9250);
DISPLAY 1.021277 (-9800 9250);
DISPLAY INVISIBLE (-9800 9250);
FORCEPROP 0 LASTPIN (-9850 9100) $PN 1
R 1
J 0
(-9860 9110);
DISPLAY 0.680851 (-9860 9110);
PAINT MONO (-9860 9110);
FORCEPROP 0 LASTPIN (-9850 8850) $PN 2
R 1
J 2
(-9860 8840);
DISPLAY 0.680851 (-9860 8840);
PAINT MONO (-9860 8840);
FORCEPROP 0 LAST VOLTAGE 25V
J 0
(-9800 9300);
DISPLAY 1.021277 (-9800 9300);
FORCEPROP 1 LAST VALUE 10UF
J 0
(-9750 9050);
DISPLAY 1.212766 (-9750 9050);
PAINT GREEN (-9750 9050);
FORCEPROP 0 LAST NO_ASSY TRUE
J 0
(-9800 8850);
DISPLAY 0.808511 (-9800 8850);
DISPLAY BOTH (-9800 8850);
FORCEPROP 0 LAST PACKAGE 0805
J 0
(-9800 9200);
DISPLAY 1.021277 (-9800 9200);
FORCEPROP 2 LAST CDS_LIB passive
J 0
(-9850 9000);
DISPLAY INVISIBLE (-9850 9000);
FORCEPROP 1 LAST CDS_LMAN_SYM_OUTLINE -50,0,50,-50
J 0
(-9850 9000);
DISPLAY 0.468085 (-9850 9000);
PAINT GREEN (-9850 9000);
DISPLAY INVISIBLE (-9850 9000);
FORCEPROP 1 LAST CLS_PN G107-0F106-EM
J 0
(-9950 9050);
DISPLAY 1.212766 (-9950 9050);
PAINT GREEN (-9950 9050);
DISPLAY INVISIBLE (-9950 9050);
FORCEPROP 1 LAST TOLERANCE 20%
J 0
(-10000 9100);
DISPLAY 1.212766 (-10000 9100);
PAINT GREEN (-10000 9100);
DISPLAY INVISIBLE (-10000 9100);
FORCEPROP 1 LAST PATH I232
J 0
(-9950 9050);
DISPLAY 1.212766 (-9950 9050);
PAINT GREEN (-9950 9050);
DISPLAY INVISIBLE (-9950 9050);
FORCEADD CONN_HDR_2X3_M_RA_TH..1
(-12850 8450);
FORCEPROP 1 LAST LOCATION P3
J 0
(-12800 8550);
DISPLAY 1.212766 (-12800 8550);
PAINT GREEN (-12800 8550);
FORCEPROP 0 LAST $SEC 1
J 0
(-12800 8750);
DISPLAY 0.680851 (-12800 8750);
PAINT MONO (-12800 8750);
DISPLAY INVISIBLE (-12800 8750);
FORCEPROP 0 LAST CDS_SEC 1
J 0
(-12800 8750);
DISPLAY 1.021277 (-12800 8750);
DISPLAY INVISIBLE (-12800 8750);
FORCEPROP 0 LASTPIN (-12950 8150) $PN 1
J 2
(-12960 8160);
DISPLAY 0.680851 (-12960 8160);
PAINT MONO (-12960 8160);
FORCEPROP 0 LASTPIN (-12950 8250) $PN 2
J 2
(-12960 8260);
DISPLAY 0.680851 (-12960 8260);
PAINT MONO (-12960 8260);
FORCEPROP 0 LASTPIN (-12950 8350) $PN 3
J 2
(-12960 8360);
DISPLAY 0.680851 (-12960 8360);
PAINT MONO (-12960 8360);
FORCEPROP 0 LASTPIN (-12450 8150) $PN 4
J 0
(-12440 8160);
DISPLAY 0.680851 (-12440 8160);
PAINT MONO (-12440 8160);
FORCEPROP 0 LASTPIN (-12450 8250) $PN 5
J 0
(-12440 8260);
DISPLAY 0.680851 (-12440 8260);
PAINT MONO (-12440 8260);
FORCEPROP 0 LASTPIN (-12450 8350) $PN 6
J 0
(-12440 8360);
DISPLAY 0.680851 (-12440 8360);
PAINT MONO (-12440 8360);
FORCEPROP 1 LAST CLS_PN G200-12517-01
J 0
(-12800 8650);
DISPLAY 1.212766 (-12800 8650);
PAINT GREEN (-12800 8650);
FORCEPROP 0 LAST PART_NUMBER 457320001
J 0
(-12500 8550);
DISPLAY 1.021277 (-12500 8550);
FORCEPROP 2 LAST CDS_LIB connector
J 0
(-12850 8450);
DISPLAY INVISIBLE (-12850 8450);
FORCEPROP 1 LAST CDS_LMAN_SYM_OUTLINE 0,0,300,-400
J 0
(-12850 8450);
DISPLAY 0.468085 (-12850 8450);
PAINT GREEN (-12850 8450);
DISPLAY INVISIBLE (-12850 8450);
FORCEPROP 1 LAST PATH I238
J 0
(-12800 8500);
DISPLAY 1.212766 (-12800 8500);
PAINT GREEN (-12800 8500);
DISPLAY INVISIBLE (-12800 8500);
FORCEADD DIODE_3F..1
(-11950 9500);
PAINT WHITE (-11950 9500);
FORCEPROP 1 LAST LOCATION CR12
J 2
(-11950 9250);
DISPLAY 1.212766 (-11950 9250);
PAINT GREEN (-11950 9250);
FORCEPROP 0 LAST $SEC 1
J 0
(-11950 9350);
DISPLAY 0.680851 (-11950 9350);
PAINT MONO (-11950 9350);
DISPLAY INVISIBLE (-11950 9350);
FORCEPROP 0 LAST CDS_SEC 1
J 0
(-11950 9350);
DISPLAY 1.021277 (-11950 9350);
DISPLAY INVISIBLE (-11950 9350);
FORCEPROP 0 LASTPIN (-12050 9450) $PN 1
J 2
(-12060 9460);
DISPLAY 0.680851 (-12060 9460);
PAINT MONO (-12060 9460);
FORCEPROP 0 LASTPIN (-12050 9350) $PN 2
J 2
(-12060 9360);
DISPLAY 0.680851 (-12060 9360);
PAINT MONO (-12060 9360);
FORCEPROP 0 LASTPIN (-11600 9400) $PN 3
J 0
(-11590 9410);
DISPLAY 0.680851 (-11590 9410);
PAINT MONO (-11590 9410);
FORCEPROP 1 LAST CLS_PN G122-10080-01
J 0
(-12100 9050);
DISPLAY 1.212766 (-12100 9050);
PAINT GREEN (-12100 9050);
FORCEPROP 0 LAST PART_NUMBER V20PW60C-M3/I
J 0
(-12100 9150);
DISPLAY 1.021277 (-12100 9150);
FORCEPROP 1 LAST CDS_LMAN_SYM_OUTLINE 0,0,250,-200
J 0
(-11950 9500);
DISPLAY 0.468085 (-11950 9500);
PAINT GREEN (-11950 9500);
DISPLAY INVISIBLE (-11950 9500);
FORCEPROP 1 LAST PATH I239
J 0
(-11650 9500);
DISPLAY 1.212766 (-11650 9500);
PAINT GREEN (-11650 9500);
DISPLAY INVISIBLE (-11650 9500);
FORCEPROP 2 LAST CDS_LIB discrete
J 0
(-11950 9500);
DISPLAY INVISIBLE (-11950 9500);
FORCEADD FERRITEBEAD..1
(-11900 9700);
FORCEPROP 1 LAST LOCATION L20
J 2
(-11950 9700);
DISPLAY 1.212766 (-11950 9700);
PAINT GREEN (-11950 9700);
FORCEPROP 0 LAST $SEC 1
J 0
(-11900 9900);
DISPLAY 0.680851 (-11900 9900);
PAINT MONO (-11900 9900);
DISPLAY INVISIBLE (-11900 9900);
FORCEPROP 0 LAST CDS_SEC 1
J 0
(-11900 9900);
DISPLAY 1.021277 (-11900 9900);
DISPLAY INVISIBLE (-11900 9900);
FORCEPROP 0 LASTPIN (-12000 9650) $PN 1
J 2
(-12010 9660);
DISPLAY 0.680851 (-12010 9660);
PAINT MONO (-12010 9660);
FORCEPROP 0 LASTPIN (-11600 9650) $PN 2
J 0
(-11590 9660);
DISPLAY 0.680851 (-11590 9660);
PAINT MONO (-11590 9660);
FORCEPROP 1 LAST VALUE 26OHM
J 0
(-11600 9700);
DISPLAY 1.212766 (-11600 9700);
PAINT GREEN (-11600 9700);
FORCEPROP 0 LAST NO_ASSY TRUE
J 0
(-11900 9850);
DISPLAY 0.808511 (-11900 9850);
DISPLAY BOTH (-11900 9850);
FORCEPROP 0 LAST PACKAGE 0603
J 0
(-11900 9750);
DISPLAY 1.021277 (-11900 9750);
FORCEPROP 2 LAST CDS_LIB passive
J 0
(-11900 9700);
DISPLAY INVISIBLE (-11900 9700);
FORCEPROP 1 LAST PATH I240
J 2
(-11950 9750);
DISPLAY 1.212766 (-11950 9750);
PAINT GREEN (-11950 9750);
DISPLAY INVISIBLE (-11950 9750);
FORCEPROP 1 LAST CDS_LMAN_SYM_OUTLINE 0,0,200,-100
J 0
(-11900 9700);
DISPLAY 0.468085 (-11900 9700);
PAINT GREEN (-11900 9700);
DISPLAY INVISIBLE (-11900 9700);
FORCEPROP 1 LAST TOLERANCE 25%
J 0
(-12000 9750);
DISPLAY 1.212766 (-12000 9750);
PAINT GREEN (-12000 9750);
DISPLAY INVISIBLE (-12000 9750);
FORCEPROP 1 LAST CLS_PN G191-10101-01
J 2
(-11950 9750);
DISPLAY 1.212766 (-11950 9750);
PAINT GREEN (-11950 9750);
DISPLAY INVISIBLE (-11950 9750);
FORCEADD OFFPAGE_IN..2
(-4250 7600);
FORCEPROP 2 LAST $XR0 25F6<> 
J 0
(-4195 7600);
DISPLAY 0.638298 (-4195 7600);
PAINT MONO (-4195 7600);
FORCEPROP 2 LAST CDS_LIB cls
J 0
(-4250 7600);
DISPLAY INVISIBLE (-4250 7600);
FORCEPROP 2 LAST PATH I243
J 0
(-4200 7700);
DISPLAY 1.021277 (-4200 7700);
DISPLAY INVISIBLE (-4200 7700);
FORCEPROP 1 LAST CDS_LMAN_SYM_OUTLINE -50,50,50,-50
J 0
(-4250 7600);
DISPLAY 0.468085 (-4250 7600);
PAINT GREEN (-4250 7600);
DISPLAY INVISIBLE (-4250 7600);
FORCEPROP 1 LAST BODY_TYPE COMMENT
J 0
(-4240 7735);
DISPLAY 0.808511 (-4240 7735);
PAINT GREEN (-4240 7735);
DISPLAY INVISIBLE (-4240 7735);
FORCEPROP 1 LAST OFFPAGE TRUE
J 0
(-4240 7655);
DISPLAY 0.808511 (-4240 7655);
PAINT GREEN (-4240 7655);
DISPLAY INVISIBLE (-4240 7655);
FORCEADD OFFPAGE_OUT..1
(-4250 7400);
FORCEPROP 2 LAST $XR0 25F6<> 
J 0
(-4195 7400);
DISPLAY 0.638298 (-4195 7400);
PAINT MONO (-4195 7400);
FORCEPROP 2 LAST CDS_LIB cls
J 0
(-4250 7400);
DISPLAY INVISIBLE (-4250 7400);
FORCEPROP 2 LAST PATH I244
J 0
(-4200 7500);
DISPLAY 1.021277 (-4200 7500);
DISPLAY INVISIBLE (-4200 7500);
FORCEPROP 1 LAST CDS_LMAN_SYM_OUTLINE -50,50,50,-50
J 0
(-4250 7400);
DISPLAY 0.468085 (-4250 7400);
PAINT GREEN (-4250 7400);
DISPLAY INVISIBLE (-4250 7400);
FORCEPROP 1 LAST BODY_TYPE COMMENT
J 0
(-4240 7535);
DISPLAY 0.808511 (-4240 7535);
PAINT GREEN (-4240 7535);
DISPLAY INVISIBLE (-4240 7535);
FORCEPROP 1 LAST OFFPAGE TRUE
J 0
(-4240 7455);
DISPLAY 0.808511 (-4240 7455);
PAINT GREEN (-4240 7455);
DISPLAY INVISIBLE (-4240 7455);
FORCEADD VCC..1
(-10800 9750);
FORCEPROP 3 LASTPIN (-10750 9700) SIG_NAME XP12R0V_IN\g
J 0
(-10740 9710);
DISPLAY 0.659574 (-10740 9710);
PAINT MONO (-10740 9710);
DISPLAY INVISIBLE (-10740 9710);
FORCEPROP 0 LAST VOLTAGE 12
J 1
(-10750 9850);
DISPLAY 1.021277 (-10750 9850);
DISPLAY BOTH (-10750 9850);
FORCEPROP 1 LAST HDL_POWER XP12R0V_IN
J 1
(-10750 9800);
DISPLAY 0.808511 (-10750 9800);
PAINT GREEN (-10750 9800);
FORCEPROP 1 LAST BODY_TYPE PLUMBING
J 0
(-10845 9707);
DISPLAY 0.340426 (-10845 9707);
PAINT GREEN (-10845 9707);
DISPLAY INVISIBLE (-10845 9707);
FORCEPROP 1 LAST PATH I245
J 0
(-10765 9840);
DISPLAY 0.808511 (-10765 9840);
PAINT GREEN (-10765 9840);
DISPLAY INVISIBLE (-10765 9840);
FORCEPROP 1 LAST CDS_LMAN_SYM_OUTLINE -250,250,250,-250
J 0
(-10800 9750);
DISPLAY 0.468085 (-10800 9750);
PAINT GREEN (-10800 9750);
DISPLAY INVISIBLE (-10800 9750);
FORCEPROP 2 LAST CDS_LIB cls
J 0
(-10800 9750);
DISPLAY INVISIBLE (-10800 9750);
FORCEADD OFFPAGE_IN..1
(-8650 8100);
FORCEPROP 2 LAST CDS_LIB cls
J 0
(-8650 8100);
DISPLAY INVISIBLE (-8650 8100);
FORCEPROP 2 LAST PATH I246
J 0
(-8600 8200);
DISPLAY 1.021277 (-8600 8200);
DISPLAY INVISIBLE (-8600 8200);
FORCEPROP 1 LAST CDS_LMAN_SYM_OUTLINE -50,50,50,-50
J 0
(-8650 8100);
DISPLAY 0.468085 (-8650 8100);
PAINT GREEN (-8650 8100);
DISPLAY INVISIBLE (-8650 8100);
FORCEPROP 1 LAST BODY_TYPE COMMENT
J 0
(-8640 8235);
DISPLAY 0.808511 (-8640 8235);
PAINT GREEN (-8640 8235);
DISPLAY INVISIBLE (-8640 8235);
FORCEPROP 1 LAST OFFPAGE TRUE
J 0
(-8640 8155);
DISPLAY 0.808511 (-8640 8155);
PAINT GREEN (-8640 8155);
DISPLAY INVISIBLE (-8640 8155);
FORCEPROP 2 LAST $XR0 25F6<> 
J 0
(-8864 8100);
DISPLAY 0.638298 (-8864 8100);
PAINT MONO (-8864 8100);
FORCEADD SHEET_A1..1
(850 1750);
FORCEPROP 2 LAST CUSTOM_TXT_CDS <XR_PAGE_TITLE>
J 0
(-14720 13100);
DISPLAY 0.638298 (-14720 13100);
PAINT PINK (-14720 13100);
FORCEPROP 1 LAST CUSTOM_TXT_CDS <DOCNO>
J 0
(-1200 2135);
DISPLAY 0.978723 (-1200 2135);
FORCEPROP 1 LAST CUSTOM_TXT_CDS <CON_PAGE_NUM>
J 0
(-1305 1800);
DISPLAY 0.978723 (-1305 1800);
FORCEPROP 1 LAST CUSTOM_TXT_CDS <DATE>
J 0
(150 1925);
DISPLAY 0.978723 (150 1925);
FORCEPROP 1 LAST CUSTOM_TXT_CDS <TITLE>
J 1
(-935 2380);
DISPLAY 0.978723 (-935 2380);
FORCEPROP 1 LAST CUSTOM_TXT_CDS <DESIGNER>
J 0
(150 2350);
DISPLAY 0.978723 (150 2350);
FORCEPROP 1 LAST CUSTOM_TXT_CDS <CON_TOTAL_PAGES>
J 0
(-995 1800);
DISPLAY 0.808511 (-995 1800);
FORCEPROP 1 LAST CUSTOM_TXT_CDS <ASSY_PN>
J 0
(-1200 1925);
DISPLAY 0.978723 (-1200 1925);
FORCEPROP 1 LAST CUSTOM_TXT_CDS <DOCREV>
J 0
(150 2125);
DISPLAY 0.978723 (150 2125);
FORCEPROP 1 LAST TITLE XP12R0V
J 0
(-1650 2600);
DISPLAY 3.042553 (-1650 2600);
PAINT GREEN (-1650 2600);
FORCEPROP 2 LAST PAGE_BORDER TRUE
J 0
(-14720 13100);
DISPLAY 0.638298 (-14720 13100);
PAINT PINK (-14720 13100);
DISPLAY INVISIBLE (-14720 13100);
FORCEPROP 1 LAST CDS_LMAN_SYM_OUTLINE -15850,11500,200,-200
J 0
(850 1750);
DISPLAY 0.468085 (850 1750);
PAINT GREEN (850 1750);
DISPLAY INVISIBLE (850 1750);
FORCEPROP 2 LAST CDS_LIB cls
J 0
(850 1750);
DISPLAY INVISIBLE (850 1750);
FORCEPROP 1 LAST COMMENT_BODY TRUE
J 0
(860 1805);
DISPLAY 0.808511 (860 1805);
PAINT GREEN (860 1805);
DISPLAY INVISIBLE (860 1805);
FORCEPROP 2 LAST CDS_XR_PAGE_TITLE CR-27 : @TIMECARD_LIB.TIMECARD(SCH_1):PAGE27
J 0
(-14720 13100);
DISPLAY 0.638298 (-14720 13100);
PAINT PINK (-14720 13100);
DISPLAY INVISIBLE (-14720 13100);
WIRE 16 -1 (-5000 8100)(-5000 8000);
WIRE 16 -1 (-8450 7100)(-8450 7250);
WIRE 16 -1 (-11150 8450)(-11150 8700);
WIRE 16 -1 (-9000 7250)(-9000 7100);
WIRE 16 -1 (-6750 8500)(-7100 8500);
WIRE 16 -1 (-7100 8500)(-7100 8600);
WIRE 16 -1 (-6750 8600)(-7100 8600);
WIRE 16 -1 (-7100 8600)(-7100 8700);
WIRE 16 -1 (-7100 8700)(-7100 8800);
WIRE 16 -1 (-6750 8700)(-7100 8700);
WIRE 16 -1 (-6750 8800)(-7100 8800);
WIRE 16 -1 (-7100 8800)(-7100 8900);
WIRE 16 -1 (-6750 8900)(-7100 8900);
WIRE 16 -1 (-7100 8900)(-7100 9000);
WIRE 16 -1 (-7100 9000)(-6750 9000);
WIRE 16 -1 (-7100 9000)(-7500 9000);
WIRE 16 -1 (-7500 9400)(-7500 9000);
WIRE 16 -1 (-7500 9400)(-5000 9400);
WIRE 16 -1 (-7500 9400)(-8450 9400);
WIRE 16 -1 (-8450 8950)(-8450 9400);
WIRE 16 -1 (-8950 9400)(-8450 9400);
WIRE 16 -1 (-4450 9400)(-5000 9400);
WIRE 16 -1 (-5000 8900)(-5000 9400);
WIRE 16 -1 (-4450 8850)(-4450 9400);
WIRE 16 -1 (-4450 9400)(-3650 9400);
WIRE 16 -1 (-8950 9100)(-8950 9400);
WIRE 16 -1 (-9450 9400)(-8950 9400);
WIRE 16 -1 (-9450 9100)(-9450 9400);
WIRE 16 -1 (-9850 9400)(-9450 9400);
WIRE 16 -1 (-9850 9100)(-9850 9400);
WIRE 16 -1 (-10250 9400)(-9850 9400);
WIRE 16 -1 (-10250 9100)(-10250 9400);
WIRE 16 -1 (-10650 9400)(-10250 9400);
WIRE 16 -1 (-10750 9400)(-10650 9400);
WIRE 16 -1 (-10650 9100)(-10650 9400);
WIRE 16 -1 (-10750 9400)(-10750 9700);
WIRE 16 -1 (-10750 9400)(-11150 9400);
WIRE 16 -1 (-11150 9200)(-11150 9400);
WIRE 16 -1 (-11300 9400)(-11150 9400);
WIRE 16 -1 (-11300 9650)(-11300 9400);
WIRE 16 -1 (-11600 9400)(-11300 9400);
WIRE 16 -1 (-11600 9650)(-11300 9650);
WIRE 16 -1 (-12450 8350)(-12250 8350);
WIRE 16 -1 (-12250 8250)(-12250 8350);
WIRE 16 -1 (-12450 8250)(-12250 8250);
WIRE 16 -1 (-12250 8150)(-12250 8250);
WIRE 16 -1 (-12450 8150)(-12250 8150);
WIRE 16 -1 (-12250 8000)(-12250 8150);
WIRE 16 -1 (-12000 9650)(-12250 9650);
WIRE 16 -1 (-12250 9650)(-12250 9450);
WIRE 16 -1 (-12250 9450)(-12050 9450);
WIRE 16 -1 (-12600 9450)(-12250 9450);
WIRE 16 -1 (-12600 9750)(-12600 9450);
WIRE 16 -1 (-13150 8250)(-13150 8150);
WIRE 16 -1 (-13150 8250)(-12950 8250);
WIRE 16 -1 (-13150 8250)(-13150 8350);
WIRE 16 -1 (-13150 8150)(-12950 8150);
WIRE 16 -1 (-12950 8350)(-13150 8350);
WIRE 16 -1 (-13250 8350)(-13150 8350);
WIRE 16 -1 (-13250 8350)(-13250 9350);
WIRE 16 -1 (-12050 9350)(-13250 9350);
WIRE 16 -1 (-13250 9750)(-13250 9350);
WIRE 16 -1 (-5550 8300)(-5350 8300);
WIRE 16 -1 (-5350 8300)(-5350 8400);
WIRE 16 -1 (-5550 8400)(-5350 8400);
WIRE 16 -1 (-5350 8400)(-5350 8500);
WIRE 16 -1 (-5550 8500)(-5350 8500);
WIRE 16 -1 (-5350 8500)(-5350 8600);
WIRE 16 -1 (-5550 8600)(-5350 8600);
WIRE 16 -1 (-5350 8600)(-5350 8700);
WIRE 16 -1 (-5550 8700)(-5350 8700);
WIRE 16 -1 (-5350 8700)(-5350 8800);
WIRE 16 -1 (-5350 8800)(-5350 8900);
WIRE 16 -1 (-5550 8800)(-5350 8800);
WIRE 16 -1 (-5550 8900)(-5350 8900);
WIRE 16 -1 (-5350 8900)(-5350 9000);
WIRE 16 -1 (-5550 9000)(-5350 9000);
WIRE 16 -1 (-5350 9000)(-3600 9000);
WIRE 16 -1 (-3600 8450)(-3600 9000);
WIRE 16 -1 (-3600 9000)(-2500 9000);
WIRE 16 -1 (-2500 9400)(-2500 9000);
WIRE 16 -1 (-2500 9000)(-2400 9000);
WIRE 16 -1 (-3600 8450)(-3050 8450);
WIRE 16 -1 (-3600 8150)(-3600 8450);
WIRE 16 -1 (-3050 8450)(-3050 8150);
WIRE 16 -1 (-2400 8750)(-2400 9000);
WIRE 16 -1 (-2400 9000)(-1800 9000);
WIRE 16 -1 (-3300 9400)(-2500 9400);
WIRE 16 -1 (-1300 9000)(-1800 9000);
WIRE 16 -1 (-1800 9000)(-1800 8750);
WIRE 16 -1 (-1300 9000)(-850 9000);
WIRE 16 -1 (-1300 8750)(-1300 9000);
WIRE 16 -1 (-850 9350)(-850 9000);
WIRE 16 -1 (-1300 8500)(-1300 8200);
WIRE 16 -1 (-1300 8200)(-1800 8200);
WIRE 16 -1 (-1300 8200)(-1300 8100);
WIRE 16 -1 (-1800 8500)(-1800 8200);
WIRE 16 -1 (-2400 8200)(-1800 8200);
WIRE 16 -1 (-2400 8250)(-2400 8200);
WIRE 16 -1 (-4000 7950)(-4000 8000);
WIRE 16 -1 (-4000 8100)(-4000 8000);
WIRE 16 -1 (-4450 8000)(-4000 8000);
WIRE 16 -1 (-4450 8100)(-4450 8000);
WIRE 16 -1 (-3050 7100)(-3050 6900);
WIRE 16 -1 (-3050 6900)(-3050 6800);
WIRE 16 -1 (-3600 6900)(-3050 6900);
WIRE 16 -1 (-3600 7100)(-3600 6900);
WIRE 16 -1 (-4250 6800)(-4250 6600);
WIRE 16 -1 (-4250 6600)(-4250 6550);
WIRE 16 -1 (-4650 6600)(-4250 6600);
WIRE 16 -1 (-4650 6800)(-4650 6600);
WIRE 16 -1 (-5450 6900)(-5550 6900);
WIRE 16 -1 (-5450 6900)(-5450 6700);
WIRE 16 -1 (-5450 6700)(-5200 6700);
WIRE 16 -1 (-5200 6550)(-5200 6700);
WIRE 16 -1 (-5200 6750)(-5200 6700);
WIRE 16 -1 (-7600 8100)(-7850 8100);
WIRE 16 -1 (-7850 8100)(-7850 7900);
WIRE 16 -1 (-7600 7900)(-7850 7900);
WIRE 16 -1 (-7850 7900)(-7850 7700);
WIRE 16 -1 (-7650 7700)(-7850 7700);
WIRE 16 -1 (-7850 7700)(-7850 7500);
WIRE 16 -1 (-7850 7100)(-7850 7500);
WIRE 16 -1 (-7650 7500)(-7850 7500);
WIRE 16 -1 (-10650 8850)(-10650 8500);
WIRE 16 -1 (-10650 8500)(-10250 8500);
WIRE 16 -1 (-10250 8500)(-9850 8500);
WIRE 16 -1 (-10250 8850)(-10250 8500);
WIRE 16 -1 (-9850 8500)(-9450 8500);
WIRE 16 -1 (-9850 8850)(-9850 8500);
WIRE 16 -1 (-8950 8500)(-9450 8500);
WIRE 16 -1 (-9450 8850)(-9450 8500);
WIRE 16 -1 (-8950 8500)(-8950 8850);
WIRE 16 -1 (-8950 8400)(-8950 8500);
WIRE 16 -1 (-9000 7500)(-9000 7700);
WIRE 16 -1 (-8450 7700)(-9000 7700);
WIRE 16 -1 (-8450 7700)(-8450 8100);
WIRE 16 -1 (-8450 7500)(-8450 7700);
WIRE 16 -1 (-8450 8100)(-8450 8300);
WIRE 16 -1 (-8600 8100)(-8450 8100);
WIRE 16 -1 (-6750 8300)(-8450 8300);
FORCEPROP 2 LAST SIG_NAME XP12R0V_A_EN
J 0
(-8410 8310);
DISPLAY 1.276596 (-8410 8310);
WIRE 16 -1 (-8450 8300)(-8450 8700);
WIRE 16 -1 (-6750 8100)(-7350 8100);
WIRE 16 -1 (-7350 7900)(-6750 7900);
WIRE 16 -1 (-3050 7500)(-3050 7900);
WIRE 16 -1 (-3050 7500)(-3050 7350);
WIRE 16 -1 (-4350 7500)(-3050 7500);
WIRE 16 -1 (-4350 7500)(-4350 7400);
WIRE 16 -1 (-5550 7500)(-4350 7500);
FORCEPROP 2 LAST SIG_NAME XP12R0V_A_FLTB
J 0
(-5360 7510);
DISPLAY 1.276596 (-5360 7510);
WIRE 16 -1 (-4350 7400)(-4300 7400);
WIRE 16 -1 (-5550 7300)(-4650 7300);
WIRE 16 -1 (-4250 7300)(-4650 7300);
FORCEPROP 2 LAST SIG_NAME XP12R0V_A_IMON
J 0
(-5360 7310);
DISPLAY 1.276596 (-5360 7310);
WIRE 16 -1 (-4650 7300)(-4650 7050);
WIRE 16 -1 (-4250 7050)(-4250 7300);
WIRE 16 -1 (-5550 7900)(-5150 7900);
WIRE 16 -1 (-5150 7900)(-5150 7800);
WIRE 16 -1 (-5150 7800)(-4650 7800);
WIRE 16 -1 (-4650 7800)(-4650 8450);
WIRE 16 -1 (-4650 8450)(-4450 8450);
WIRE 16 -1 (-4450 8500)(-4450 8450);
WIRE 16 -1 (-4450 8350)(-4450 8450);
WIRE 16 -1 (-4450 8500)(-4000 8500);
FORCEPROP 2 LAST SIG_NAME XP12R0V_A_OV
J 0
(-4410 8510);
DISPLAY 1.276596 (-4410 8510);
WIRE 16 -1 (-4450 8600)(-4450 8500);
WIRE 16 -1 (-4000 8350)(-4000 8500);
WIRE 16 -1 (-3600 7700)(-3600 7900);
WIRE 16 -1 (-3600 7700)(-3600 7350);
WIRE 16 -1 (-4350 7700)(-3600 7700);
WIRE 16 -1 (-4350 7600)(-4350 7700);
WIRE 16 -1 (-5550 7700)(-4350 7700);
FORCEPROP 2 LAST SIG_NAME XP12R0V_A_PG
J 0
(-5360 7710);
DISPLAY 1.276596 (-5360 7710);
WIRE 16 -1 (-4350 7600)(-4300 7600);
WIRE 16 -1 (-6750 7500)(-7400 7500);
FORCEPROP 2 LAST SIG_NAME XP12R0V_A_ISET
J 0
(-7360 7460);
DISPLAY 0.808511 (-7360 7460);
WIRE 16 -1 (-6750 7700)(-7400 7700);
FORCEPROP 2 LAST SIG_NAME XP12R0V_A_TIMER
J 0
(-7360 7660);
DISPLAY 0.808511 (-7360 7660);
WIRE 16 -1 (-5200 7000)(-5200 7100);
WIRE 16 -1 (-5200 7100)(-5550 7100);
FORCEPROP 2 LAST SIG_NAME XP12R0V_A_SS
J 0
(-5510 7110);
DISPLAY 1.276596 (-5510 7110);
WIRE 8 -1 (-1750 6900)(-1000 6900);
WIRE 8 -1 (-1750 7100)(-1750 6900);
WIRE 8 -1 (-2400 6900)(-1750 6900);
WIRE 8 -1 (-1000 7100)(-1000 6900);
WIRE 8 -1 (-1000 7300)(-1000 7100);
WIRE 8 -1 (-1750 7100)(-1000 7100);
WIRE 8 -1 (-2400 7100)(-2400 6900);
WIRE 8 -1 (-2400 7100)(-1750 7100);
WIRE 8 -1 (-1750 7300)(-1750 7100);
WIRE 8 -1 (-1750 7300)(-1000 7300);
WIRE 8 -1 (-1750 7500)(-1750 7300);
WIRE 8 -1 (-2400 7300)(-1750 7300);
WIRE 8 -1 (-2400 7300)(-2400 7100);
WIRE 8 -1 (-1000 7500)(-1000 7300);
WIRE 8 -1 (-1000 7700)(-1000 7500);
WIRE 8 -1 (-1750 7500)(-1000 7500);
WIRE 8 -1 (-2400 7500)(-2400 7300);
WIRE 8 -1 (-2400 7500)(-1750 7500);
WIRE 8 -1 (-1750 7700)(-1750 7500);
WIRE 8 -1 (-1750 7700)(-1000 7700);
WIRE 8 -1 (-2400 7700)(-1750 7700);
WIRE 8 -1 (-2400 7700)(-2400 7500);
WIRE 16 -1 (-5150 8450)(-5150 8100);
WIRE 16 -1 (-5150 8450)(-5000 8450);
WIRE 16 -1 (-5150 8100)(-5550 8100);
WIRE 16 -1 (-5000 8650)(-5000 8450);
WIRE 16 -1 (-5000 8350)(-5000 8450);
FORCEPROP 2 LAST SIG_NAME XP12R0V_A_AVIN
R 1
J 0
(-5160 8110);
DISPLAY 1.276596 (-5160 8110);
DOT 1 (-4350 7500);
DOT 1 (-4350 7700);
DOT 1 (-3600 7700);
DOT 1 (-2500 9000);
DOT 1 (-8450 9400);
DOT 1 (-7850 7500);
DOT 1 (-7850 7900);
DOT 1 (-7850 7700);
DOT 1 (-12250 8150);
DOT 1 (-8450 7700);
DOT 1 (-13150 8250);
DOT 1 (-13150 8350);
DOT 1 (-13250 9350);
DOT 1 (-12250 8250);
DOT 1 (-12250 9450);
DOT 1 (-11300 9400);
DOT 1 (-11150 9400);
DOT 1 (-10650 9400);
DOT 1 (-10250 8500);
DOT 1 (-9850 8500);
DOT 1 (-9450 8500);
DOT 1 (-8950 8500);
DOT 1 (-8450 8300);
DOT 1 (-8950 9400);
DOT 1 (-5350 8800);
DOT 1 (-1300 9000);
DOT 1 (-1800 9000);
DOT 1 (-2400 9000);
DOT 1 (-3600 9000);
DOT 1 (-3600 8450);
DOT 1 (-4450 9400);
DOT 1 (-4450 8500);
DOT 1 (-4450 8450);
DOT 1 (-5000 9400);
DOT 1 (-5000 8450);
DOT 1 (-5350 9000);
DOT 1 (-5350 8900);
DOT 1 (-5350 8700);
DOT 1 (-5350 8600);
DOT 1 (-5350 8500);
DOT 1 (-7100 8600);
DOT 1 (-7100 8700);
DOT 1 (-7100 8900);
DOT 1 (-7100 9000);
DOT 1 (-5350 8400);
DOT 1 (-1300 8200);
DOT 1 (-1000 7500);
DOT 1 (-1000 7300);
DOT 1 (-1000 7100);
DOT 1 (-1800 8200);
DOT 1 (-1750 7700);
DOT 1 (-1750 7500);
DOT 1 (-2400 7500);
DOT 1 (-1750 7300);
DOT 1 (-1750 7100);
DOT 1 (-1750 6900);
DOT 1 (-2400 7300);
DOT 1 (-2400 7100);
DOT 1 (-3050 7500);
DOT 1 (-3050 6900);
DOT 1 (-4000 8000);
DOT 1 (-4650 7300);
DOT 1 (-4250 6600);
DOT 1 (-5200 6700);
DOT 1 (-7500 9400);
DOT 1 (-9850 9400);
DOT 1 (-9450 9400);
DOT 1 (-7100 8800);
DOT 1 (-10750 9400);
DOT 1 (-10250 9400);
DOT 1 (-8450 8100);
FORCENOTE
1.67A
(-9700 9600) 0;
DISPLAY LEFT (-9700 9600);
DISPLAY 1.276596 (-9700 9600);
FORCENOTE
XP12R0V INPUT
(-8400 11750) 0;
DISPLAY LEFT (-8400 11750);
DISPLAY 4.914894 (-8400 11750);
FORCENOTE
1.67A
(-1550 9150) 0;
DISPLAY LEFT (-1550 9150);
DISPLAY 1.276596 (-1550 9150);
FORCENOTE
1.67A
(-1500 7150) 0;
DISPLAY LEFT (-1500 7150);
DISPLAY 1.276596 (-1500 7150);
FORCENOTE
13.64V
(-1500 6950) 0;
DISPLAY LEFT (-1500 6950);
DISPLAY 1.276596 (-1500 6950);
FORCENOTE
12V
(-1500 7550) 0;
DISPLAY LEFT (-1500 7550);
DISPLAY 1.276596 (-1500 7550);
FORCENOTE
4.81A
(-1500 7350) 0;
DISPLAY LEFT (-1500 7350);
DISPLAY 1.276596 (-1500 7350);
FORCENOTE
XP12R0V
(-2100 7800) 0;
DISPLAY LEFT (-2100 7800);
DISPLAY 1.276596 (-2100 7800);
FORCENOTE
VIN
(-2150 7550) 0;
DISPLAY LEFT (-2150 7550);
DISPLAY 1.276596 (-2150 7550);
FORCENOTE
ILIM
(-2150 7350) 0;
DISPLAY LEFT (-2150 7350);
DISPLAY 1.276596 (-2150 7350);
FORCENOTE
OVP
(-2150 6950) 0;
DISPLAY LEFT (-2150 6950);
DISPLAY 1.276596 (-2150 6950);
FORCENOTE
IMAX
(-2150 7150) 0;
DISPLAY LEFT (-2150 7150);
DISPLAY 1.276596 (-2150 7150);
FORCENOTE
INTERNAL PULL-UP
(-7650 8350) 0;
DISPLAY LEFT (-7650 8350);
DISPLAY 1.021277 (-7650 8350);
QUIT
